FILE_TYPE = MACRO_DRAWING;
SET COLOR_WIRE YELLOW;
SET COLOR_PROP ORANGE;
SET COLOR_DOT WHITE;
SET COLOR_ARC YELLOW;
SET COLOR_BODY GREEN;
SET COLOR_NOTE PURPLE;
SET PROP_DISPLAY VALUE;
SET PAGE_NUMBER P85;
FORCEADD GND..1
(-650 1750);
FORCEPROP 3 LASTPIN (-650 1800) SIG_NAME GND\g
J 0
(-640 1810);
DISPLAY 0.659574 (-640 1810);
PAINT MONO (-640 1810);
DISPLAY INVISIBLE (-640 1810);
FORCEPROP 1 LAST SIZE 1B
J 0
(-575 1700);
DISPLAY 0.851064 (-575 1700);
PAINT GREEN (-575 1700);
DISPLAY INVISIBLE (-575 1700);
FORCEPROP 2 LAST CDS_LIB mstr_symbols
J 0
(-650 1750);
DISPLAY 0.723404 (-650 1750);
DISPLAY INVISIBLE (-650 1750);
FORCEPROP 1 LAST BODY_TYPE PLUMBING
J 0
(-695 1707);
DISPLAY 0.340426 (-695 1707);
PAINT GREEN (-695 1707);
DISPLAY INVISIBLE (-695 1707);
FORCEPROP 1 LAST PATH I115
J 0
(-575 1750);
DISPLAY 0.872340 (-575 1750);
PAINT GREEN (-575 1750);
DISPLAY INVISIBLE (-575 1750);
FORCEPROP 1 LAST VOLTAGE 0.0
J 0
(-695 1707);
DISPLAY 0.723404 (-695 1707);
PAINT SKYBLUE (-695 1707);
DISPLAY INVISIBLE (-695 1707);
FORCEPROP 1 LAST HDL_POWER GND
J 0
(-650 1900);
DISPLAY 0.851064 (-650 1900);
PAINT GREEN (-650 1900);
DISPLAY INVISIBLE (-650 1900);
FORCEADD GND..1
(-2250 1950);
FORCEPROP 3 LASTPIN (-2250 2000) SIG_NAME GND\g
J 0
(-2240 2010);
DISPLAY 0.659574 (-2240 2010);
PAINT MONO (-2240 2010);
DISPLAY INVISIBLE (-2240 2010);
FORCEPROP 1 LAST SIZE 1B
J 0
(-2175 1900);
DISPLAY 0.851064 (-2175 1900);
PAINT GREEN (-2175 1900);
DISPLAY INVISIBLE (-2175 1900);
FORCEPROP 2 LAST CDS_LIB mstr_symbols
J 0
(-2250 1950);
DISPLAY 0.723404 (-2250 1950);
DISPLAY INVISIBLE (-2250 1950);
FORCEPROP 1 LAST BODY_TYPE PLUMBING
J 0
(-2295 1907);
DISPLAY 0.340426 (-2295 1907);
PAINT GREEN (-2295 1907);
DISPLAY INVISIBLE (-2295 1907);
FORCEPROP 1 LAST PATH I116
J 0
(-2175 1950);
DISPLAY 0.872340 (-2175 1950);
PAINT GREEN (-2175 1950);
DISPLAY INVISIBLE (-2175 1950);
FORCEPROP 1 LAST VOLTAGE 0.0
J 0
(-2295 1907);
DISPLAY 0.723404 (-2295 1907);
PAINT SKYBLUE (-2295 1907);
DISPLAY INVISIBLE (-2295 1907);
FORCEPROP 1 LAST HDL_POWER GND
J 0
(-2250 2100);
DISPLAY 0.851064 (-2250 2100);
PAINT GREEN (-2250 2100);
DISPLAY INVISIBLE (-2250 2100);
FORCEADD TAP..1
R 2
(-7750 4025);
FORCEPROP 3 LASTPIN (-7700 4025) SIG_NAME M_A_CPU0_SA_CB<7>
J 0
(-7690 4035);
DISPLAY 0.659574 (-7690 4035);
PAINT MONO (-7690 4035);
DISPLAY INVISIBLE (-7690 4035);
FORCEPROP 1 LASTPIN (-7700 4025) BN 7
J 2
(-7688 4033);
DISPLAY 0.489362 (-7688 4033);
PAINT GREEN (-7688 4033);
FORCEPROP 2 LAST CDS_LIB mstr_standard
J 0
(-7750 4025);
DISPLAY 0.723404 (-7750 4025);
PAINT MONO (-7750 4025);
DISPLAY INVISIBLE (-7750 4025);
FORCEPROP 1 LAST BODY_TYPE PLUMBING
J 2
(-7750 4075);
DISPLAY 0.872340 (-7750 4075);
PAINT GREEN (-7750 4075);
DISPLAY INVISIBLE (-7750 4075);
FORCEPROP 1 LAST HDL_TAP TRUE
J 2
(-8075 3900);
DISPLAY 0.872340 (-8075 3900);
DISPLAY INVISIBLE (-8075 3900);
FORCEPROP 1 LAST PATH I210
J 2
(-7748 4025);
DISPLAY 0.872340 (-7748 4025);
PAINT GREEN (-7748 4025);
DISPLAY INVISIBLE (-7748 4025);
FORCEADD TAP..1
R 2
(-7750 3925);
FORCEPROP 3 LASTPIN (-7700 3925) SIG_NAME M_A_CPU0_SA_CB<5>
J 0
(-7690 3935);
DISPLAY 0.659574 (-7690 3935);
PAINT MONO (-7690 3935);
DISPLAY INVISIBLE (-7690 3935);
FORCEPROP 1 LASTPIN (-7700 3925) BN 5
J 2
(-7688 3933);
DISPLAY 0.489362 (-7688 3933);
PAINT GREEN (-7688 3933);
FORCEPROP 2 LAST CDS_LIB mstr_standard
J 0
(-7750 3925);
DISPLAY 0.723404 (-7750 3925);
PAINT MONO (-7750 3925);
DISPLAY INVISIBLE (-7750 3925);
FORCEPROP 1 LAST BODY_TYPE PLUMBING
J 2
(-7750 3975);
DISPLAY 0.872340 (-7750 3975);
PAINT GREEN (-7750 3975);
DISPLAY INVISIBLE (-7750 3975);
FORCEPROP 1 LAST HDL_TAP TRUE
J 2
(-8075 3800);
DISPLAY 0.872340 (-8075 3800);
DISPLAY INVISIBLE (-8075 3800);
FORCEPROP 1 LAST PATH I211
J 2
(-7748 3925);
DISPLAY 0.872340 (-7748 3925);
PAINT GREEN (-7748 3925);
DISPLAY INVISIBLE (-7748 3925);
FORCEADD TAP..1
R 2
(-7750 3975);
FORCEPROP 3 LASTPIN (-7700 3975) SIG_NAME M_A_CPU0_SA_CB<6>
J 0
(-7690 3985);
DISPLAY 0.659574 (-7690 3985);
PAINT MONO (-7690 3985);
DISPLAY INVISIBLE (-7690 3985);
FORCEPROP 1 LASTPIN (-7700 3975) BN 6
J 2
(-7688 3983);
DISPLAY 0.489362 (-7688 3983);
PAINT GREEN (-7688 3983);
FORCEPROP 2 LAST CDS_LIB mstr_standard
J 0
(-7750 3975);
DISPLAY 0.723404 (-7750 3975);
PAINT MONO (-7750 3975);
DISPLAY INVISIBLE (-7750 3975);
FORCEPROP 1 LAST BODY_TYPE PLUMBING
J 2
(-7750 4025);
DISPLAY 0.872340 (-7750 4025);
PAINT GREEN (-7750 4025);
DISPLAY INVISIBLE (-7750 4025);
FORCEPROP 1 LAST HDL_TAP TRUE
J 2
(-8075 3850);
DISPLAY 0.872340 (-8075 3850);
DISPLAY INVISIBLE (-8075 3850);
FORCEPROP 1 LAST PATH I212
J 2
(-7748 3975);
DISPLAY 0.872340 (-7748 3975);
PAINT GREEN (-7748 3975);
DISPLAY INVISIBLE (-7748 3975);
FORCEADD TAP..1
R 2
(-7750 3825);
FORCEPROP 3 LASTPIN (-7700 3825) SIG_NAME M_A_CPU0_SA_CB<3>
J 0
(-7690 3835);
DISPLAY 0.659574 (-7690 3835);
PAINT MONO (-7690 3835);
DISPLAY INVISIBLE (-7690 3835);
FORCEPROP 1 LASTPIN (-7700 3825) BN 3
J 2
(-7688 3833);
DISPLAY 0.489362 (-7688 3833);
PAINT GREEN (-7688 3833);
FORCEPROP 2 LAST CDS_LIB mstr_standard
J 0
(-7750 3825);
DISPLAY 0.723404 (-7750 3825);
PAINT MONO (-7750 3825);
DISPLAY INVISIBLE (-7750 3825);
FORCEPROP 1 LAST BODY_TYPE PLUMBING
J 2
(-7750 3875);
DISPLAY 0.872340 (-7750 3875);
PAINT GREEN (-7750 3875);
DISPLAY INVISIBLE (-7750 3875);
FORCEPROP 1 LAST HDL_TAP TRUE
J 2
(-8075 3700);
DISPLAY 0.872340 (-8075 3700);
DISPLAY INVISIBLE (-8075 3700);
FORCEPROP 1 LAST PATH I213
J 2
(-7748 3825);
DISPLAY 0.872340 (-7748 3825);
PAINT GREEN (-7748 3825);
DISPLAY INVISIBLE (-7748 3825);
FORCEADD TAP..1
R 2
(-7750 3875);
FORCEPROP 3 LASTPIN (-7700 3875) SIG_NAME M_A_CPU0_SA_CB<4>
J 0
(-7690 3885);
DISPLAY 0.659574 (-7690 3885);
PAINT MONO (-7690 3885);
DISPLAY INVISIBLE (-7690 3885);
FORCEPROP 1 LASTPIN (-7700 3875) BN 4
J 2
(-7688 3883);
DISPLAY 0.489362 (-7688 3883);
PAINT GREEN (-7688 3883);
FORCEPROP 2 LAST CDS_LIB mstr_standard
J 0
(-7750 3875);
DISPLAY 0.723404 (-7750 3875);
PAINT MONO (-7750 3875);
DISPLAY INVISIBLE (-7750 3875);
FORCEPROP 1 LAST BODY_TYPE PLUMBING
J 2
(-7750 3925);
DISPLAY 0.872340 (-7750 3925);
PAINT GREEN (-7750 3925);
DISPLAY INVISIBLE (-7750 3925);
FORCEPROP 1 LAST HDL_TAP TRUE
J 2
(-8075 3750);
DISPLAY 0.872340 (-8075 3750);
DISPLAY INVISIBLE (-8075 3750);
FORCEPROP 1 LAST PATH I214
J 2
(-7748 3875);
DISPLAY 0.872340 (-7748 3875);
PAINT GREEN (-7748 3875);
DISPLAY INVISIBLE (-7748 3875);
FORCEADD TAP..1
R 2
(-7750 3775);
FORCEPROP 3 LASTPIN (-7700 3775) SIG_NAME M_A_CPU0_SA_CB<2>
J 0
(-7690 3785);
DISPLAY 0.659574 (-7690 3785);
PAINT MONO (-7690 3785);
DISPLAY INVISIBLE (-7690 3785);
FORCEPROP 1 LASTPIN (-7700 3775) BN 2
J 2
(-7688 3783);
DISPLAY 0.489362 (-7688 3783);
PAINT GREEN (-7688 3783);
FORCEPROP 2 LAST CDS_LIB mstr_standard
J 0
(-7750 3775);
DISPLAY 0.723404 (-7750 3775);
PAINT MONO (-7750 3775);
DISPLAY INVISIBLE (-7750 3775);
FORCEPROP 1 LAST BODY_TYPE PLUMBING
J 2
(-7750 3825);
DISPLAY 0.872340 (-7750 3825);
PAINT GREEN (-7750 3825);
DISPLAY INVISIBLE (-7750 3825);
FORCEPROP 1 LAST HDL_TAP TRUE
J 2
(-8075 3650);
DISPLAY 0.872340 (-8075 3650);
DISPLAY INVISIBLE (-8075 3650);
FORCEPROP 1 LAST PATH I215
J 2
(-7748 3775);
DISPLAY 0.872340 (-7748 3775);
PAINT GREEN (-7748 3775);
DISPLAY INVISIBLE (-7748 3775);
FORCEADD TAP..1
R 2
(-7750 3725);
FORCEPROP 3 LASTPIN (-7700 3725) SIG_NAME M_A_CPU0_SA_CB<1>
J 0
(-7690 3735);
DISPLAY 0.659574 (-7690 3735);
PAINT MONO (-7690 3735);
DISPLAY INVISIBLE (-7690 3735);
FORCEPROP 1 LASTPIN (-7700 3725) BN 1
J 2
(-7688 3733);
DISPLAY 0.489362 (-7688 3733);
PAINT GREEN (-7688 3733);
FORCEPROP 2 LAST CDS_LIB mstr_standard
J 0
(-7750 3725);
DISPLAY 0.723404 (-7750 3725);
PAINT MONO (-7750 3725);
DISPLAY INVISIBLE (-7750 3725);
FORCEPROP 1 LAST BODY_TYPE PLUMBING
J 2
(-7750 3775);
DISPLAY 0.872340 (-7750 3775);
PAINT GREEN (-7750 3775);
DISPLAY INVISIBLE (-7750 3775);
FORCEPROP 1 LAST HDL_TAP TRUE
J 2
(-8075 3600);
DISPLAY 0.872340 (-8075 3600);
DISPLAY INVISIBLE (-8075 3600);
FORCEPROP 1 LAST PATH I216
J 2
(-7748 3725);
DISPLAY 0.872340 (-7748 3725);
PAINT GREEN (-7748 3725);
DISPLAY INVISIBLE (-7748 3725);
FORCEADD TAP..1
R 2
(-7750 3675);
FORCEPROP 3 LASTPIN (-7700 3675) SIG_NAME M_A_CPU0_SA_CB<0>
J 0
(-7690 3685);
DISPLAY 0.659574 (-7690 3685);
PAINT MONO (-7690 3685);
DISPLAY INVISIBLE (-7690 3685);
FORCEPROP 1 LASTPIN (-7700 3675) BN 0
J 2
(-7688 3683);
DISPLAY 0.489362 (-7688 3683);
PAINT GREEN (-7688 3683);
FORCEPROP 2 LAST CDS_LIB mstr_standard
J 0
(-7750 3675);
DISPLAY 0.723404 (-7750 3675);
PAINT MONO (-7750 3675);
DISPLAY INVISIBLE (-7750 3675);
FORCEPROP 1 LAST BODY_TYPE PLUMBING
J 2
(-7750 3725);
DISPLAY 0.872340 (-7750 3725);
PAINT GREEN (-7750 3725);
DISPLAY INVISIBLE (-7750 3725);
FORCEPROP 1 LAST HDL_TAP TRUE
J 2
(-8075 3550);
DISPLAY 0.872340 (-8075 3550);
DISPLAY INVISIBLE (-8075 3550);
FORCEPROP 1 LAST PATH I217
J 2
(-7748 3675);
DISPLAY 0.872340 (-7748 3675);
PAINT GREEN (-7748 3675);
DISPLAY INVISIBLE (-7748 3675);
FORCEADD OFFPAGE..6
(-8350 4075);
FORCEPROP 2 LAST $XR0 10 
J 0
(-8629 4075);
DISPLAY 0.638298 (-8629 4075);
PAINT MONO (-8629 4075);
FORCEPROP 2 LAST PATH I218
J 0
(-8600 4125);
DISPLAY 0.808511 (-8600 4125);
DISPLAY INVISIBLE (-8600 4125);
FORCEPROP 1 LAST COMMENT_BODY TRUE
J 0
(-8250 4000);
DISPLAY 0.872340 (-8250 4000);
PAINT GREEN (-8250 4000);
DISPLAY INVISIBLE (-8250 4000);
FORCEPROP 1 LAST OFFPAGE TRUE
J 0
(-8025 3950);
DISPLAY 0.872340 (-8025 3950);
PAINT GREEN (-8025 3950);
DISPLAY INVISIBLE (-8025 3950);
FORCEPROP 2 LAST CDS_LIB mstr_standard
J 0
(-8350 4075);
DISPLAY 0.723404 (-8350 4075);
PAINT MONO (-8350 4075);
DISPLAY INVISIBLE (-8350 4075);
FORCEADD TAP..1
R 2
(-7750 5375);
FORCEPROP 3 LASTPIN (-7700 5375) SIG_NAME M_A_CPU0_SA_CA<5>
J 0
(-7690 5385);
DISPLAY 0.659574 (-7690 5385);
PAINT MONO (-7690 5385);
DISPLAY INVISIBLE (-7690 5385);
FORCEPROP 1 LASTPIN (-7700 5375) BN 5
J 2
(-7688 5383);
DISPLAY 0.489362 (-7688 5383);
PAINT GREEN (-7688 5383);
FORCEPROP 2 LAST CDS_LIB mstr_standard
J 0
(-7750 5375);
DISPLAY 0.723404 (-7750 5375);
PAINT MONO (-7750 5375);
DISPLAY INVISIBLE (-7750 5375);
FORCEPROP 1 LAST BODY_TYPE PLUMBING
J 2
(-7750 5425);
DISPLAY 0.872340 (-7750 5425);
PAINT GREEN (-7750 5425);
DISPLAY INVISIBLE (-7750 5425);
FORCEPROP 1 LAST HDL_TAP TRUE
J 2
(-8075 5250);
DISPLAY 0.872340 (-8075 5250);
DISPLAY INVISIBLE (-8075 5250);
FORCEPROP 1 LAST PATH I227
J 2
(-7748 5375);
DISPLAY 0.872340 (-7748 5375);
PAINT GREEN (-7748 5375);
DISPLAY INVISIBLE (-7748 5375);
FORCEADD TAP..1
R 2
(-7750 5325);
FORCEPROP 3 LASTPIN (-7700 5325) SIG_NAME M_A_CPU0_SA_CA<4>
J 0
(-7690 5335);
DISPLAY 0.659574 (-7690 5335);
PAINT MONO (-7690 5335);
DISPLAY INVISIBLE (-7690 5335);
FORCEPROP 1 LASTPIN (-7700 5325) BN 4
J 2
(-7688 5333);
DISPLAY 0.489362 (-7688 5333);
PAINT GREEN (-7688 5333);
FORCEPROP 2 LAST CDS_LIB mstr_standard
J 0
(-7750 5325);
DISPLAY 0.723404 (-7750 5325);
PAINT MONO (-7750 5325);
DISPLAY INVISIBLE (-7750 5325);
FORCEPROP 1 LAST BODY_TYPE PLUMBING
J 2
(-7750 5375);
DISPLAY 0.872340 (-7750 5375);
PAINT GREEN (-7750 5375);
DISPLAY INVISIBLE (-7750 5375);
FORCEPROP 1 LAST HDL_TAP TRUE
J 2
(-8075 5200);
DISPLAY 0.872340 (-8075 5200);
DISPLAY INVISIBLE (-8075 5200);
FORCEPROP 1 LAST PATH I228
J 2
(-7748 5325);
DISPLAY 0.872340 (-7748 5325);
PAINT GREEN (-7748 5325);
DISPLAY INVISIBLE (-7748 5325);
FORCEADD TAP..1
R 2
(-7750 5425);
FORCEPROP 3 LASTPIN (-7700 5425) SIG_NAME M_A_CPU0_SA_CA<6>
J 0
(-7690 5435);
DISPLAY 0.659574 (-7690 5435);
PAINT MONO (-7690 5435);
DISPLAY INVISIBLE (-7690 5435);
FORCEPROP 1 LASTPIN (-7700 5425) BN 6
J 2
(-7688 5433);
DISPLAY 0.489362 (-7688 5433);
PAINT GREEN (-7688 5433);
FORCEPROP 2 LAST CDS_LIB mstr_standard
J 0
(-7750 5425);
DISPLAY 0.723404 (-7750 5425);
PAINT MONO (-7750 5425);
DISPLAY INVISIBLE (-7750 5425);
FORCEPROP 1 LAST BODY_TYPE PLUMBING
J 2
(-7750 5475);
DISPLAY 0.872340 (-7750 5475);
PAINT GREEN (-7750 5475);
DISPLAY INVISIBLE (-7750 5475);
FORCEPROP 1 LAST HDL_TAP TRUE
J 2
(-8075 5300);
DISPLAY 0.872340 (-8075 5300);
DISPLAY INVISIBLE (-8075 5300);
FORCEPROP 1 LAST PATH I229
J 2
(-7748 5425);
DISPLAY 0.872340 (-7748 5425);
PAINT GREEN (-7748 5425);
DISPLAY INVISIBLE (-7748 5425);
FORCEADD TAP..1
R 2
(-7750 5275);
FORCEPROP 3 LASTPIN (-7700 5275) SIG_NAME M_A_CPU0_SA_CA<3>
J 0
(-7690 5285);
DISPLAY 0.659574 (-7690 5285);
PAINT MONO (-7690 5285);
DISPLAY INVISIBLE (-7690 5285);
FORCEPROP 1 LASTPIN (-7700 5275) BN 3
J 2
(-7688 5283);
DISPLAY 0.489362 (-7688 5283);
PAINT GREEN (-7688 5283);
FORCEPROP 2 LAST CDS_LIB mstr_standard
J 0
(-7750 5275);
DISPLAY 0.723404 (-7750 5275);
PAINT MONO (-7750 5275);
DISPLAY INVISIBLE (-7750 5275);
FORCEPROP 1 LAST BODY_TYPE PLUMBING
J 2
(-7750 5325);
DISPLAY 0.872340 (-7750 5325);
PAINT GREEN (-7750 5325);
DISPLAY INVISIBLE (-7750 5325);
FORCEPROP 1 LAST HDL_TAP TRUE
J 2
(-8075 5150);
DISPLAY 0.872340 (-8075 5150);
DISPLAY INVISIBLE (-8075 5150);
FORCEPROP 1 LAST PATH I230
J 2
(-7748 5275);
DISPLAY 0.872340 (-7748 5275);
PAINT GREEN (-7748 5275);
DISPLAY INVISIBLE (-7748 5275);
FORCEADD TAP..1
R 2
(-7750 5225);
FORCEPROP 3 LASTPIN (-7700 5225) SIG_NAME M_A_CPU0_SA_CA<2>
J 0
(-7690 5235);
DISPLAY 0.659574 (-7690 5235);
PAINT MONO (-7690 5235);
DISPLAY INVISIBLE (-7690 5235);
FORCEPROP 1 LASTPIN (-7700 5225) BN 2
J 2
(-7688 5233);
DISPLAY 0.489362 (-7688 5233);
PAINT GREEN (-7688 5233);
FORCEPROP 2 LAST CDS_LIB mstr_standard
J 0
(-7750 5225);
DISPLAY 0.723404 (-7750 5225);
PAINT MONO (-7750 5225);
DISPLAY INVISIBLE (-7750 5225);
FORCEPROP 1 LAST BODY_TYPE PLUMBING
J 2
(-7750 5275);
DISPLAY 0.872340 (-7750 5275);
PAINT GREEN (-7750 5275);
DISPLAY INVISIBLE (-7750 5275);
FORCEPROP 1 LAST HDL_TAP TRUE
J 2
(-8075 5100);
DISPLAY 0.872340 (-8075 5100);
DISPLAY INVISIBLE (-8075 5100);
FORCEPROP 1 LAST PATH I231
J 2
(-7748 5225);
DISPLAY 0.872340 (-7748 5225);
PAINT GREEN (-7748 5225);
DISPLAY INVISIBLE (-7748 5225);
FORCEADD TAP..1
R 2
(-7750 5175);
FORCEPROP 3 LASTPIN (-7700 5175) SIG_NAME M_A_CPU0_SA_CA<1>
J 0
(-7690 5185);
DISPLAY 0.659574 (-7690 5185);
PAINT MONO (-7690 5185);
DISPLAY INVISIBLE (-7690 5185);
FORCEPROP 1 LASTPIN (-7700 5175) BN 1
J 2
(-7688 5183);
DISPLAY 0.489362 (-7688 5183);
PAINT GREEN (-7688 5183);
FORCEPROP 2 LAST CDS_LIB mstr_standard
J 0
(-7750 5175);
DISPLAY 0.723404 (-7750 5175);
PAINT MONO (-7750 5175);
DISPLAY INVISIBLE (-7750 5175);
FORCEPROP 1 LAST BODY_TYPE PLUMBING
J 2
(-7750 5225);
DISPLAY 0.872340 (-7750 5225);
PAINT GREEN (-7750 5225);
DISPLAY INVISIBLE (-7750 5225);
FORCEPROP 1 LAST HDL_TAP TRUE
J 2
(-8075 5050);
DISPLAY 0.872340 (-8075 5050);
DISPLAY INVISIBLE (-8075 5050);
FORCEPROP 1 LAST PATH I232
J 2
(-7748 5175);
DISPLAY 0.872340 (-7748 5175);
PAINT GREEN (-7748 5175);
DISPLAY INVISIBLE (-7748 5175);
FORCEADD TAP..1
R 2
(-7750 5125);
FORCEPROP 3 LASTPIN (-7700 5125) SIG_NAME M_A_CPU0_SA_CA<0>
J 0
(-7690 5135);
DISPLAY 0.659574 (-7690 5135);
PAINT MONO (-7690 5135);
DISPLAY INVISIBLE (-7690 5135);
FORCEPROP 1 LASTPIN (-7700 5125) BN 0
J 2
(-7688 5133);
DISPLAY 0.489362 (-7688 5133);
PAINT GREEN (-7688 5133);
FORCEPROP 2 LAST CDS_LIB mstr_standard
J 0
(-7750 5125);
DISPLAY 0.723404 (-7750 5125);
PAINT MONO (-7750 5125);
DISPLAY INVISIBLE (-7750 5125);
FORCEPROP 1 LAST BODY_TYPE PLUMBING
J 2
(-7750 5175);
DISPLAY 0.872340 (-7750 5175);
PAINT GREEN (-7750 5175);
DISPLAY INVISIBLE (-7750 5175);
FORCEPROP 1 LAST HDL_TAP TRUE
J 2
(-8075 5000);
DISPLAY 0.872340 (-8075 5000);
DISPLAY INVISIBLE (-8075 5000);
FORCEPROP 1 LAST PATH I233
J 2
(-7748 5125);
DISPLAY 0.872340 (-7748 5125);
PAINT GREEN (-7748 5125);
DISPLAY INVISIBLE (-7748 5125);
FORCEADD TAP..1
R 2
(-7750 5025);
FORCEPROP 3 LASTPIN (-7700 5025) SIG_NAME M_A_CPU0_SB_CA<6>
J 0
(-7690 5035);
DISPLAY 0.659574 (-7690 5035);
PAINT MONO (-7690 5035);
DISPLAY INVISIBLE (-7690 5035);
FORCEPROP 1 LASTPIN (-7700 5025) BN 6
J 2
(-7688 5033);
DISPLAY 0.489362 (-7688 5033);
PAINT GREEN (-7688 5033);
FORCEPROP 2 LAST CDS_LIB mstr_standard
J 0
(-7750 5025);
DISPLAY 0.723404 (-7750 5025);
PAINT MONO (-7750 5025);
DISPLAY INVISIBLE (-7750 5025);
FORCEPROP 1 LAST BODY_TYPE PLUMBING
J 2
(-7750 5075);
DISPLAY 0.872340 (-7750 5075);
PAINT GREEN (-7750 5075);
DISPLAY INVISIBLE (-7750 5075);
FORCEPROP 1 LAST HDL_TAP TRUE
J 2
(-8075 4900);
DISPLAY 0.872340 (-8075 4900);
DISPLAY INVISIBLE (-8075 4900);
FORCEPROP 1 LAST PATH I235
J 2
(-7748 5025);
DISPLAY 0.872340 (-7748 5025);
PAINT GREEN (-7748 5025);
DISPLAY INVISIBLE (-7748 5025);
FORCEADD TAP..1
R 2
(-7750 4975);
FORCEPROP 3 LASTPIN (-7700 4975) SIG_NAME M_A_CPU0_SB_CA<5>
J 0
(-7690 4985);
DISPLAY 0.659574 (-7690 4985);
PAINT MONO (-7690 4985);
DISPLAY INVISIBLE (-7690 4985);
FORCEPROP 1 LASTPIN (-7700 4975) BN 5
J 2
(-7688 4983);
DISPLAY 0.489362 (-7688 4983);
PAINT GREEN (-7688 4983);
FORCEPROP 2 LAST CDS_LIB mstr_standard
J 0
(-7750 4975);
DISPLAY 0.723404 (-7750 4975);
PAINT MONO (-7750 4975);
DISPLAY INVISIBLE (-7750 4975);
FORCEPROP 1 LAST BODY_TYPE PLUMBING
J 2
(-7750 5025);
DISPLAY 0.872340 (-7750 5025);
PAINT GREEN (-7750 5025);
DISPLAY INVISIBLE (-7750 5025);
FORCEPROP 1 LAST HDL_TAP TRUE
J 2
(-8075 4850);
DISPLAY 0.872340 (-8075 4850);
DISPLAY INVISIBLE (-8075 4850);
FORCEPROP 1 LAST PATH I236
J 2
(-7748 4975);
DISPLAY 0.872340 (-7748 4975);
PAINT GREEN (-7748 4975);
DISPLAY INVISIBLE (-7748 4975);
FORCEADD TAP..1
R 2
(-7750 4925);
FORCEPROP 3 LASTPIN (-7700 4925) SIG_NAME M_A_CPU0_SB_CA<4>
J 0
(-7690 4935);
DISPLAY 0.659574 (-7690 4935);
PAINT MONO (-7690 4935);
DISPLAY INVISIBLE (-7690 4935);
FORCEPROP 1 LASTPIN (-7700 4925) BN 4
J 2
(-7688 4933);
DISPLAY 0.489362 (-7688 4933);
PAINT GREEN (-7688 4933);
FORCEPROP 2 LAST CDS_LIB mstr_standard
J 0
(-7750 4925);
DISPLAY 0.723404 (-7750 4925);
PAINT MONO (-7750 4925);
DISPLAY INVISIBLE (-7750 4925);
FORCEPROP 1 LAST BODY_TYPE PLUMBING
J 2
(-7750 4975);
DISPLAY 0.872340 (-7750 4975);
PAINT GREEN (-7750 4975);
DISPLAY INVISIBLE (-7750 4975);
FORCEPROP 1 LAST HDL_TAP TRUE
J 2
(-8075 4800);
DISPLAY 0.872340 (-8075 4800);
DISPLAY INVISIBLE (-8075 4800);
FORCEPROP 1 LAST PATH I237
J 2
(-7748 4925);
DISPLAY 0.872340 (-7748 4925);
PAINT GREEN (-7748 4925);
DISPLAY INVISIBLE (-7748 4925);
FORCEADD TAP..1
R 2
(-7750 4825);
FORCEPROP 3 LASTPIN (-7700 4825) SIG_NAME M_A_CPU0_SB_CA<2>
J 0
(-7690 4835);
DISPLAY 0.659574 (-7690 4835);
PAINT MONO (-7690 4835);
DISPLAY INVISIBLE (-7690 4835);
FORCEPROP 1 LASTPIN (-7700 4825) BN 2
J 2
(-7688 4833);
DISPLAY 0.489362 (-7688 4833);
PAINT GREEN (-7688 4833);
FORCEPROP 2 LAST CDS_LIB mstr_standard
J 0
(-7750 4825);
DISPLAY 0.723404 (-7750 4825);
PAINT MONO (-7750 4825);
DISPLAY INVISIBLE (-7750 4825);
FORCEPROP 1 LAST BODY_TYPE PLUMBING
J 2
(-7750 4875);
DISPLAY 0.872340 (-7750 4875);
PAINT GREEN (-7750 4875);
DISPLAY INVISIBLE (-7750 4875);
FORCEPROP 1 LAST HDL_TAP TRUE
J 2
(-8075 4700);
DISPLAY 0.872340 (-8075 4700);
DISPLAY INVISIBLE (-8075 4700);
FORCEPROP 1 LAST PATH I238
J 2
(-7748 4825);
DISPLAY 0.872340 (-7748 4825);
PAINT GREEN (-7748 4825);
DISPLAY INVISIBLE (-7748 4825);
FORCEADD TAP..1
R 2
(-7750 4725);
FORCEPROP 3 LASTPIN (-7700 4725) SIG_NAME M_A_CPU0_SB_CA<0>
J 0
(-7690 4735);
DISPLAY 0.659574 (-7690 4735);
PAINT MONO (-7690 4735);
DISPLAY INVISIBLE (-7690 4735);
FORCEPROP 1 LASTPIN (-7700 4725) BN 0
J 2
(-7688 4733);
DISPLAY 0.489362 (-7688 4733);
PAINT GREEN (-7688 4733);
FORCEPROP 2 LAST CDS_LIB mstr_standard
J 0
(-7750 4725);
DISPLAY 0.723404 (-7750 4725);
PAINT MONO (-7750 4725);
DISPLAY INVISIBLE (-7750 4725);
FORCEPROP 1 LAST BODY_TYPE PLUMBING
J 2
(-7750 4775);
DISPLAY 0.872340 (-7750 4775);
PAINT GREEN (-7750 4775);
DISPLAY INVISIBLE (-7750 4775);
FORCEPROP 1 LAST HDL_TAP TRUE
J 2
(-8075 4600);
DISPLAY 0.872340 (-8075 4600);
DISPLAY INVISIBLE (-8075 4600);
FORCEPROP 1 LAST PATH I239
J 2
(-7748 4725);
DISPLAY 0.872340 (-7748 4725);
PAINT GREEN (-7748 4725);
DISPLAY INVISIBLE (-7748 4725);
FORCEADD TAP..1
R 2
(-7750 4775);
FORCEPROP 3 LASTPIN (-7700 4775) SIG_NAME M_A_CPU0_SB_CA<1>
J 0
(-7690 4785);
DISPLAY 0.659574 (-7690 4785);
PAINT MONO (-7690 4785);
DISPLAY INVISIBLE (-7690 4785);
FORCEPROP 1 LASTPIN (-7700 4775) BN 1
J 2
(-7688 4783);
DISPLAY 0.489362 (-7688 4783);
PAINT GREEN (-7688 4783);
FORCEPROP 2 LAST CDS_LIB mstr_standard
J 0
(-7750 4775);
DISPLAY 0.723404 (-7750 4775);
PAINT MONO (-7750 4775);
DISPLAY INVISIBLE (-7750 4775);
FORCEPROP 1 LAST BODY_TYPE PLUMBING
J 2
(-7750 4825);
DISPLAY 0.872340 (-7750 4825);
PAINT GREEN (-7750 4825);
DISPLAY INVISIBLE (-7750 4825);
FORCEPROP 1 LAST HDL_TAP TRUE
J 2
(-8075 4650);
DISPLAY 0.872340 (-8075 4650);
DISPLAY INVISIBLE (-8075 4650);
FORCEPROP 1 LAST PATH I240
J 2
(-7748 4775);
DISPLAY 0.872340 (-7748 4775);
PAINT GREEN (-7748 4775);
DISPLAY INVISIBLE (-7748 4775);
FORCEADD TAP..1
R 2
(-7750 4875);
FORCEPROP 3 LASTPIN (-7700 4875) SIG_NAME M_A_CPU0_SB_CA<3>
J 0
(-7690 4885);
DISPLAY 0.659574 (-7690 4885);
PAINT MONO (-7690 4885);
DISPLAY INVISIBLE (-7690 4885);
FORCEPROP 1 LASTPIN (-7700 4875) BN 3
J 2
(-7688 4883);
DISPLAY 0.489362 (-7688 4883);
PAINT GREEN (-7688 4883);
FORCEPROP 2 LAST CDS_LIB mstr_standard
J 0
(-7750 4875);
DISPLAY 0.723404 (-7750 4875);
PAINT MONO (-7750 4875);
DISPLAY INVISIBLE (-7750 4875);
FORCEPROP 1 LAST BODY_TYPE PLUMBING
J 2
(-7750 4925);
DISPLAY 0.872340 (-7750 4925);
PAINT GREEN (-7750 4925);
DISPLAY INVISIBLE (-7750 4925);
FORCEPROP 1 LAST HDL_TAP TRUE
J 2
(-8075 4750);
DISPLAY 0.872340 (-8075 4750);
DISPLAY INVISIBLE (-8075 4750);
FORCEPROP 1 LAST PATH I241
J 2
(-7748 4875);
DISPLAY 0.872340 (-7748 4875);
PAINT GREEN (-7748 4875);
DISPLAY INVISIBLE (-7748 4875);
FORCEADD OFFPAGE..1
(-8350 5475);
FORCEPROP 2 LAST $XR0 10 
J 0
(-8601 5475);
DISPLAY 0.638298 (-8601 5475);
PAINT MONO (-8601 5475);
FORCEPROP 2 LAST PATH I243
J 0
(-8600 5525);
DISPLAY 0.808511 (-8600 5525);
DISPLAY INVISIBLE (-8600 5525);
FORCEPROP 1 LAST COMMENT_BODY TRUE
J 0
(-8225 5375);
DISPLAY 0.872340 (-8225 5375);
PAINT GREEN (-8225 5375);
DISPLAY INVISIBLE (-8225 5375);
FORCEPROP 1 LAST OFFPAGE TRUE
J 0
(-8025 5350);
DISPLAY 0.872340 (-8025 5350);
PAINT GREEN (-8025 5350);
DISPLAY INVISIBLE (-8025 5350);
FORCEPROP 2 LAST CDS_LIB mstr_standard
J 0
(-8350 5475);
DISPLAY 0.723404 (-8350 5475);
PAINT MONO (-8350 5475);
DISPLAY INVISIBLE (-8350 5475);
FORCEADD OFFPAGE..1
(-8350 4175);
FORCEPROP 2 LAST $XR0 10 
J 0
(-8601 4175);
DISPLAY 0.638298 (-8601 4175);
PAINT MONO (-8601 4175);
FORCEPROP 2 LAST PATH I252
J 0
(-8600 4225);
DISPLAY 0.808511 (-8600 4225);
DISPLAY INVISIBLE (-8600 4225);
FORCEPROP 1 LAST COMMENT_BODY TRUE
J 0
(-8225 4075);
DISPLAY 0.872340 (-8225 4075);
PAINT GREEN (-8225 4075);
DISPLAY INVISIBLE (-8225 4075);
FORCEPROP 1 LAST OFFPAGE TRUE
J 0
(-8025 4050);
DISPLAY 0.872340 (-8025 4050);
PAINT GREEN (-8025 4050);
DISPLAY INVISIBLE (-8025 4050);
FORCEPROP 2 LAST CDS_LIB mstr_standard
J 0
(-8350 4175);
DISPLAY 0.723404 (-8350 4175);
PAINT MONO (-8350 4175);
DISPLAY INVISIBLE (-8350 4175);
FORCEADD OFFPAGE..1
(-8350 4125);
FORCEPROP 2 LAST $XR0 10 
J 0
(-8601 4125);
DISPLAY 0.638298 (-8601 4125);
PAINT MONO (-8601 4125);
FORCEPROP 2 LAST PATH I253
J 0
(-8300 4200);
DISPLAY 0.808511 (-8300 4200);
DISPLAY INVISIBLE (-8300 4200);
FORCEPROP 1 LAST COMMENT_BODY TRUE
J 0
(-8225 4025);
DISPLAY 0.872340 (-8225 4025);
PAINT GREEN (-8225 4025);
DISPLAY INVISIBLE (-8225 4025);
FORCEPROP 1 LAST OFFPAGE TRUE
J 0
(-8025 4000);
DISPLAY 0.872340 (-8025 4000);
PAINT GREEN (-8025 4000);
DISPLAY INVISIBLE (-8025 4000);
FORCEPROP 2 LAST CDS_LIB mstr_standard
J 0
(-8350 4125);
DISPLAY 0.808511 (-8350 4125);
DISPLAY INVISIBLE (-8350 4125);
FORCEADD OFFPAGE..1
(-8350 4575);
FORCEPROP 2 LAST $XR0 10 
J 0
(-8601 4575);
DISPLAY 0.638298 (-8601 4575);
PAINT MONO (-8601 4575);
FORCEPROP 2 LAST PATH I256
J 0
(-8300 4650);
DISPLAY 0.808511 (-8300 4650);
DISPLAY INVISIBLE (-8300 4650);
FORCEPROP 1 LAST COMMENT_BODY TRUE
J 0
(-8225 4475);
DISPLAY 0.872340 (-8225 4475);
PAINT GREEN (-8225 4475);
DISPLAY INVISIBLE (-8225 4475);
FORCEPROP 1 LAST OFFPAGE TRUE
J 0
(-8025 4450);
DISPLAY 0.872340 (-8025 4450);
PAINT GREEN (-8025 4450);
DISPLAY INVISIBLE (-8025 4450);
FORCEPROP 2 LAST CDS_LIB mstr_standard
J 0
(-8350 4575);
DISPLAY 0.808511 (-8350 4575);
DISPLAY INVISIBLE (-8350 4575);
FORCEADD OFFPAGE..1
(-8350 4625);
FORCEPROP 2 LAST $XR0 10 
J 0
(-8601 4625);
DISPLAY 0.638298 (-8601 4625);
PAINT MONO (-8601 4625);
FORCEPROP 2 LAST PATH I257
J 0
(-8300 4700);
DISPLAY 0.808511 (-8300 4700);
DISPLAY INVISIBLE (-8300 4700);
FORCEPROP 1 LAST COMMENT_BODY TRUE
J 0
(-8225 4525);
DISPLAY 0.872340 (-8225 4525);
PAINT GREEN (-8225 4525);
DISPLAY INVISIBLE (-8225 4525);
FORCEPROP 1 LAST OFFPAGE TRUE
J 0
(-8025 4500);
DISPLAY 0.872340 (-8025 4500);
PAINT GREEN (-8025 4500);
DISPLAY INVISIBLE (-8025 4500);
FORCEPROP 2 LAST CDS_LIB mstr_standard
J 0
(-8350 4625);
DISPLAY 0.723404 (-8350 4625);
PAINT MONO (-8350 4625);
DISPLAY INVISIBLE (-8350 4625);
FORCEADD OFFPAGE..1
(-8350 4425);
FORCEPROP 2 LAST $XR0 10 
J 0
(-8601 4425);
DISPLAY 0.638298 (-8601 4425);
PAINT MONO (-8601 4425);
FORCEPROP 2 LAST PATH I258
J 0
(-8300 4500);
DISPLAY 0.808511 (-8300 4500);
DISPLAY INVISIBLE (-8300 4500);
FORCEPROP 1 LAST COMMENT_BODY TRUE
J 0
(-8225 4325);
DISPLAY 0.872340 (-8225 4325);
PAINT GREEN (-8225 4325);
DISPLAY INVISIBLE (-8225 4325);
FORCEPROP 1 LAST OFFPAGE TRUE
J 0
(-8025 4300);
DISPLAY 0.872340 (-8025 4300);
PAINT GREEN (-8025 4300);
DISPLAY INVISIBLE (-8025 4300);
FORCEPROP 2 LAST CDS_LIB mstr_standard
J 0
(-8350 4425);
DISPLAY 0.808511 (-8350 4425);
DISPLAY INVISIBLE (-8350 4425);
FORCEADD OFFPAGE..1
(-8350 4475);
FORCEPROP 2 LAST $XR0 10 
J 0
(-8601 4475);
DISPLAY 0.638298 (-8601 4475);
PAINT MONO (-8601 4475);
FORCEPROP 2 LAST PATH I259
J 0
(-8300 4550);
DISPLAY 0.808511 (-8300 4550);
DISPLAY INVISIBLE (-8300 4550);
FORCEPROP 1 LAST COMMENT_BODY TRUE
J 0
(-8225 4375);
DISPLAY 0.872340 (-8225 4375);
PAINT GREEN (-8225 4375);
DISPLAY INVISIBLE (-8225 4375);
FORCEPROP 1 LAST OFFPAGE TRUE
J 0
(-8025 4350);
DISPLAY 0.872340 (-8025 4350);
PAINT GREEN (-8025 4350);
DISPLAY INVISIBLE (-8025 4350);
FORCEPROP 2 LAST CDS_LIB mstr_standard
J 0
(-8350 4475);
DISPLAY 0.723404 (-8350 4475);
PAINT MONO (-8350 4475);
DISPLAY INVISIBLE (-8350 4475);
FORCEADD OFFPAGE..1
(-8350 4275);
FORCEPROP 2 LAST $XR0 10 
J 0
(-8601 4275);
DISPLAY 0.638298 (-8601 4275);
PAINT MONO (-8601 4275);
FORCEPROP 2 LAST PATH I260
J 0
(-8300 4350);
DISPLAY 0.808511 (-8300 4350);
DISPLAY INVISIBLE (-8300 4350);
FORCEPROP 1 LAST COMMENT_BODY TRUE
J 0
(-8225 4175);
DISPLAY 0.872340 (-8225 4175);
PAINT GREEN (-8225 4175);
DISPLAY INVISIBLE (-8225 4175);
FORCEPROP 1 LAST OFFPAGE TRUE
J 0
(-8025 4150);
DISPLAY 0.872340 (-8025 4150);
PAINT GREEN (-8025 4150);
DISPLAY INVISIBLE (-8025 4150);
FORCEPROP 2 LAST CDS_LIB mstr_standard
J 0
(-8350 4275);
DISPLAY 0.808511 (-8350 4275);
DISPLAY INVISIBLE (-8350 4275);
FORCEADD OFFPAGE..1
(-8350 4325);
FORCEPROP 2 LAST $XR0 10 
J 0
(-8601 4325);
DISPLAY 0.638298 (-8601 4325);
PAINT MONO (-8601 4325);
FORCEPROP 2 LAST PATH I261
J 0
(-8300 4400);
DISPLAY 0.808511 (-8300 4400);
DISPLAY INVISIBLE (-8300 4400);
FORCEPROP 1 LAST COMMENT_BODY TRUE
J 0
(-8225 4225);
DISPLAY 0.872340 (-8225 4225);
PAINT GREEN (-8225 4225);
DISPLAY INVISIBLE (-8225 4225);
FORCEPROP 1 LAST OFFPAGE TRUE
J 0
(-8025 4200);
DISPLAY 0.872340 (-8025 4200);
PAINT GREEN (-8025 4200);
DISPLAY INVISIBLE (-8025 4200);
FORCEPROP 2 LAST CDS_LIB mstr_standard
J 0
(-8350 4325);
DISPLAY 0.723404 (-8350 4325);
PAINT MONO (-8350 4325);
DISPLAY INVISIBLE (-8350 4325);
FORCEADD OFFPAGE..5
(-8350 2025);
FORCEPROP 2 LAST $XR0 10 
J 0
(-8574 2025);
DISPLAY 0.638298 (-8574 2025);
PAINT MONO (-8574 2025);
FORCEPROP 2 LAST PATH I265
J 0
(-8300 2100);
DISPLAY 0.808511 (-8300 2100);
DISPLAY INVISIBLE (-8300 2100);
FORCEPROP 1 LAST COMMENT_BODY TRUE
J 0
(-8250 1950);
DISPLAY 0.872340 (-8250 1950);
PAINT GREEN (-8250 1950);
DISPLAY INVISIBLE (-8250 1950);
FORCEPROP 1 LAST OFFPAGE TRUE
J 0
(-8025 1900);
DISPLAY 0.872340 (-8025 1900);
PAINT GREEN (-8025 1900);
DISPLAY INVISIBLE (-8025 1900);
FORCEPROP 2 LAST CDS_LIB mstr_standard
J 0
(-8350 2025);
DISPLAY 0.808511 (-8350 2025);
DISPLAY INVISIBLE (-8350 2025);
FORCEADD OFFPAGE..5
(-8350 1975);
FORCEPROP 2 LAST $XR0 10 
J 0
(-8574 1975);
DISPLAY 0.638298 (-8574 1975);
PAINT MONO (-8574 1975);
FORCEPROP 2 LAST PATH I266
J 0
(-8300 2050);
DISPLAY 0.808511 (-8300 2050);
DISPLAY INVISIBLE (-8300 2050);
FORCEPROP 1 LAST COMMENT_BODY TRUE
J 0
(-8250 1900);
DISPLAY 0.872340 (-8250 1900);
PAINT GREEN (-8250 1900);
DISPLAY INVISIBLE (-8250 1900);
FORCEPROP 1 LAST OFFPAGE TRUE
J 0
(-8025 1850);
DISPLAY 0.872340 (-8025 1850);
PAINT GREEN (-8025 1850);
DISPLAY INVISIBLE (-8025 1850);
FORCEPROP 2 LAST CDS_LIB mstr_standard
J 0
(-8350 1975);
DISPLAY 0.808511 (-8350 1975);
DISPLAY INVISIBLE (-8350 1975);
FORCEADD OFFPAGE..1
(-8350 5075);
FORCEPROP 2 LAST $XR0 10 
J 0
(-8601 5075);
DISPLAY 0.638298 (-8601 5075);
PAINT MONO (-8601 5075);
FORCEPROP 2 LAST PATH I366
J 0
(-8300 5150);
DISPLAY 0.808511 (-8300 5150);
DISPLAY INVISIBLE (-8300 5150);
FORCEPROP 1 LAST COMMENT_BODY TRUE
J 0
(-8225 4975);
DISPLAY 0.872340 (-8225 4975);
PAINT GREEN (-8225 4975);
DISPLAY INVISIBLE (-8225 4975);
FORCEPROP 1 LAST OFFPAGE TRUE
J 0
(-8025 4950);
DISPLAY 0.872340 (-8025 4950);
PAINT GREEN (-8025 4950);
DISPLAY INVISIBLE (-8025 4950);
FORCEPROP 2 LAST CDS_LIB mstr_standard
J 0
(-8350 5075);
DISPLAY 0.723404 (-8350 5075);
PAINT MONO (-8350 5075);
DISPLAY INVISIBLE (-8350 5075);
FORCEADD TAP..1
R 2
(-7750 3575);
FORCEPROP 3 LASTPIN (-7700 3575) SIG_NAME M_A_CPU0_SB_CB<7>
J 0
(-7690 3585);
DISPLAY 0.659574 (-7690 3585);
PAINT MONO (-7690 3585);
DISPLAY INVISIBLE (-7690 3585);
FORCEPROP 1 LASTPIN (-7700 3575) BN 7
J 2
(-7688 3583);
DISPLAY 0.489362 (-7688 3583);
PAINT GREEN (-7688 3583);
FORCEPROP 2 LAST CDS_LIB mstr_standard
J 0
(-7750 3575);
DISPLAY 0.723404 (-7750 3575);
PAINT MONO (-7750 3575);
DISPLAY INVISIBLE (-7750 3575);
FORCEPROP 1 LAST BODY_TYPE PLUMBING
J 2
(-7750 3625);
DISPLAY 0.872340 (-7750 3625);
PAINT GREEN (-7750 3625);
DISPLAY INVISIBLE (-7750 3625);
FORCEPROP 1 LAST HDL_TAP TRUE
J 2
(-8075 3450);
DISPLAY 0.872340 (-8075 3450);
DISPLAY INVISIBLE (-8075 3450);
FORCEPROP 1 LAST PATH I367
J 2
(-7748 3575);
DISPLAY 0.872340 (-7748 3575);
PAINT GREEN (-7748 3575);
DISPLAY INVISIBLE (-7748 3575);
FORCEADD TAP..1
R 2
(-7750 3525);
FORCEPROP 3 LASTPIN (-7700 3525) SIG_NAME M_A_CPU0_SB_CB<6>
J 0
(-7690 3535);
DISPLAY 0.659574 (-7690 3535);
PAINT MONO (-7690 3535);
DISPLAY INVISIBLE (-7690 3535);
FORCEPROP 1 LASTPIN (-7700 3525) BN 6
J 2
(-7688 3533);
DISPLAY 0.489362 (-7688 3533);
PAINT GREEN (-7688 3533);
FORCEPROP 2 LAST CDS_LIB mstr_standard
J 0
(-7750 3525);
DISPLAY 0.723404 (-7750 3525);
PAINT MONO (-7750 3525);
DISPLAY INVISIBLE (-7750 3525);
FORCEPROP 1 LAST BODY_TYPE PLUMBING
J 2
(-7750 3575);
DISPLAY 0.872340 (-7750 3575);
PAINT GREEN (-7750 3575);
DISPLAY INVISIBLE (-7750 3575);
FORCEPROP 1 LAST HDL_TAP TRUE
J 2
(-8075 3400);
DISPLAY 0.872340 (-8075 3400);
DISPLAY INVISIBLE (-8075 3400);
FORCEPROP 1 LAST PATH I368
J 2
(-7748 3525);
DISPLAY 0.872340 (-7748 3525);
PAINT GREEN (-7748 3525);
DISPLAY INVISIBLE (-7748 3525);
FORCEADD TAP..1
R 2
(-7750 3475);
FORCEPROP 3 LASTPIN (-7700 3475) SIG_NAME M_A_CPU0_SB_CB<5>
J 0
(-7690 3485);
DISPLAY 0.659574 (-7690 3485);
PAINT MONO (-7690 3485);
DISPLAY INVISIBLE (-7690 3485);
FORCEPROP 1 LASTPIN (-7700 3475) BN 5
J 2
(-7688 3483);
DISPLAY 0.489362 (-7688 3483);
PAINT GREEN (-7688 3483);
FORCEPROP 2 LAST CDS_LIB mstr_standard
J 0
(-7750 3475);
DISPLAY 0.723404 (-7750 3475);
PAINT MONO (-7750 3475);
DISPLAY INVISIBLE (-7750 3475);
FORCEPROP 1 LAST BODY_TYPE PLUMBING
J 2
(-7750 3525);
DISPLAY 0.872340 (-7750 3525);
PAINT GREEN (-7750 3525);
DISPLAY INVISIBLE (-7750 3525);
FORCEPROP 1 LAST HDL_TAP TRUE
J 2
(-8075 3350);
DISPLAY 0.872340 (-8075 3350);
DISPLAY INVISIBLE (-8075 3350);
FORCEPROP 1 LAST PATH I369
J 2
(-7748 3475);
DISPLAY 0.872340 (-7748 3475);
PAINT GREEN (-7748 3475);
DISPLAY INVISIBLE (-7748 3475);
FORCEADD TAP..1
R 2
(-7750 3425);
FORCEPROP 3 LASTPIN (-7700 3425) SIG_NAME M_A_CPU0_SB_CB<4>
J 0
(-7690 3435);
DISPLAY 0.659574 (-7690 3435);
PAINT MONO (-7690 3435);
DISPLAY INVISIBLE (-7690 3435);
FORCEPROP 1 LASTPIN (-7700 3425) BN 4
J 2
(-7688 3433);
DISPLAY 0.489362 (-7688 3433);
PAINT GREEN (-7688 3433);
FORCEPROP 2 LAST CDS_LIB mstr_standard
J 0
(-7750 3425);
DISPLAY 0.723404 (-7750 3425);
PAINT MONO (-7750 3425);
DISPLAY INVISIBLE (-7750 3425);
FORCEPROP 1 LAST BODY_TYPE PLUMBING
J 2
(-7750 3475);
DISPLAY 0.872340 (-7750 3475);
PAINT GREEN (-7750 3475);
DISPLAY INVISIBLE (-7750 3475);
FORCEPROP 1 LAST HDL_TAP TRUE
J 2
(-8075 3300);
DISPLAY 0.872340 (-8075 3300);
DISPLAY INVISIBLE (-8075 3300);
FORCEPROP 1 LAST PATH I370
J 2
(-7748 3425);
DISPLAY 0.872340 (-7748 3425);
PAINT GREEN (-7748 3425);
DISPLAY INVISIBLE (-7748 3425);
FORCEADD TAP..1
R 2
(-7750 3375);
FORCEPROP 3 LASTPIN (-7700 3375) SIG_NAME M_A_CPU0_SB_CB<3>
J 0
(-7690 3385);
DISPLAY 0.659574 (-7690 3385);
PAINT MONO (-7690 3385);
DISPLAY INVISIBLE (-7690 3385);
FORCEPROP 1 LASTPIN (-7700 3375) BN 3
J 2
(-7688 3383);
DISPLAY 0.489362 (-7688 3383);
PAINT GREEN (-7688 3383);
FORCEPROP 2 LAST CDS_LIB mstr_standard
J 0
(-7750 3375);
DISPLAY 0.723404 (-7750 3375);
PAINT MONO (-7750 3375);
DISPLAY INVISIBLE (-7750 3375);
FORCEPROP 1 LAST BODY_TYPE PLUMBING
J 2
(-7750 3425);
DISPLAY 0.872340 (-7750 3425);
PAINT GREEN (-7750 3425);
DISPLAY INVISIBLE (-7750 3425);
FORCEPROP 1 LAST HDL_TAP TRUE
J 2
(-8075 3250);
DISPLAY 0.872340 (-8075 3250);
DISPLAY INVISIBLE (-8075 3250);
FORCEPROP 1 LAST PATH I371
J 2
(-7748 3375);
DISPLAY 0.872340 (-7748 3375);
PAINT GREEN (-7748 3375);
DISPLAY INVISIBLE (-7748 3375);
FORCEADD TAP..1
R 2
(-7750 3225);
FORCEPROP 3 LASTPIN (-7700 3225) SIG_NAME M_A_CPU0_SB_CB<0>
J 0
(-7690 3235);
DISPLAY 0.659574 (-7690 3235);
PAINT MONO (-7690 3235);
DISPLAY INVISIBLE (-7690 3235);
FORCEPROP 1 LASTPIN (-7700 3225) BN 0
J 2
(-7688 3233);
DISPLAY 0.489362 (-7688 3233);
PAINT GREEN (-7688 3233);
FORCEPROP 2 LAST CDS_LIB mstr_standard
J 0
(-7750 3225);
DISPLAY 0.723404 (-7750 3225);
PAINT MONO (-7750 3225);
DISPLAY INVISIBLE (-7750 3225);
FORCEPROP 1 LAST BODY_TYPE PLUMBING
J 2
(-7750 3275);
DISPLAY 0.872340 (-7750 3275);
PAINT GREEN (-7750 3275);
DISPLAY INVISIBLE (-7750 3275);
FORCEPROP 1 LAST HDL_TAP TRUE
J 2
(-8075 3100);
DISPLAY 0.872340 (-8075 3100);
DISPLAY INVISIBLE (-8075 3100);
FORCEPROP 1 LAST PATH I372
J 2
(-7748 3225);
DISPLAY 0.872340 (-7748 3225);
PAINT GREEN (-7748 3225);
DISPLAY INVISIBLE (-7748 3225);
FORCEADD TAP..1
R 2
(-7750 3275);
FORCEPROP 3 LASTPIN (-7700 3275) SIG_NAME M_A_CPU0_SB_CB<1>
J 0
(-7690 3285);
DISPLAY 0.659574 (-7690 3285);
PAINT MONO (-7690 3285);
DISPLAY INVISIBLE (-7690 3285);
FORCEPROP 1 LASTPIN (-7700 3275) BN 1
J 2
(-7688 3283);
DISPLAY 0.489362 (-7688 3283);
PAINT GREEN (-7688 3283);
FORCEPROP 2 LAST CDS_LIB mstr_standard
J 0
(-7750 3275);
DISPLAY 0.723404 (-7750 3275);
PAINT MONO (-7750 3275);
DISPLAY INVISIBLE (-7750 3275);
FORCEPROP 1 LAST BODY_TYPE PLUMBING
J 2
(-7750 3325);
DISPLAY 0.872340 (-7750 3325);
PAINT GREEN (-7750 3325);
DISPLAY INVISIBLE (-7750 3325);
FORCEPROP 1 LAST HDL_TAP TRUE
J 2
(-8075 3150);
DISPLAY 0.872340 (-8075 3150);
DISPLAY INVISIBLE (-8075 3150);
FORCEPROP 1 LAST PATH I373
J 2
(-7748 3275);
DISPLAY 0.872340 (-7748 3275);
PAINT GREEN (-7748 3275);
DISPLAY INVISIBLE (-7748 3275);
FORCEADD TAP..1
R 2
(-7750 3325);
FORCEPROP 3 LASTPIN (-7700 3325) SIG_NAME M_A_CPU0_SB_CB<2>
J 0
(-7690 3335);
DISPLAY 0.659574 (-7690 3335);
PAINT MONO (-7690 3335);
DISPLAY INVISIBLE (-7690 3335);
FORCEPROP 1 LASTPIN (-7700 3325) BN 2
J 2
(-7688 3333);
DISPLAY 0.489362 (-7688 3333);
PAINT GREEN (-7688 3333);
FORCEPROP 2 LAST CDS_LIB mstr_standard
J 0
(-7750 3325);
DISPLAY 0.723404 (-7750 3325);
PAINT MONO (-7750 3325);
DISPLAY INVISIBLE (-7750 3325);
FORCEPROP 1 LAST BODY_TYPE PLUMBING
J 2
(-7750 3375);
DISPLAY 0.872340 (-7750 3375);
PAINT GREEN (-7750 3375);
DISPLAY INVISIBLE (-7750 3375);
FORCEPROP 1 LAST HDL_TAP TRUE
J 2
(-8075 3200);
DISPLAY 0.872340 (-8075 3200);
DISPLAY INVISIBLE (-8075 3200);
FORCEPROP 1 LAST PATH I374
J 2
(-7748 3325);
DISPLAY 0.872340 (-7748 3325);
PAINT GREEN (-7748 3325);
DISPLAY INVISIBLE (-7748 3325);
FORCEADD OFFPAGE..6
(-8350 3625);
FORCEPROP 2 LAST $XR0 10 
J 0
(-8629 3625);
DISPLAY 0.638298 (-8629 3625);
PAINT MONO (-8629 3625);
FORCEPROP 2 LAST PATH I376
J 0
(-8300 3700);
DISPLAY 0.808511 (-8300 3700);
DISPLAY INVISIBLE (-8300 3700);
FORCEPROP 1 LAST COMMENT_BODY TRUE
J 0
(-8250 3550);
DISPLAY 0.872340 (-8250 3550);
PAINT GREEN (-8250 3550);
DISPLAY INVISIBLE (-8250 3550);
FORCEPROP 1 LAST OFFPAGE TRUE
J 0
(-8025 3500);
DISPLAY 0.872340 (-8025 3500);
PAINT GREEN (-8025 3500);
DISPLAY INVISIBLE (-8025 3500);
FORCEPROP 2 LAST CDS_LIB mstr_standard
J 0
(-8350 3625);
DISPLAY 0.723404 (-8350 3625);
PAINT MONO (-8350 3625);
DISPLAY INVISIBLE (-8350 3625);
FORCEADD OFFPAGE..1
(-8350 3125);
FORCEPROP 2 LAST $XR0 10 
J 0
(-8601 3125);
DISPLAY 0.638298 (-8601 3125);
PAINT MONO (-8601 3125);
FORCEPROP 2 LAST PATH I378
J 0
(-8550 3350);
DISPLAY 0.808511 (-8550 3350);
DISPLAY INVISIBLE (-8550 3350);
FORCEPROP 1 LAST COMMENT_BODY TRUE
J 0
(-8225 3025);
DISPLAY 0.872340 (-8225 3025);
PAINT GREEN (-8225 3025);
DISPLAY INVISIBLE (-8225 3025);
FORCEPROP 1 LAST OFFPAGE TRUE
J 0
(-8025 3000);
DISPLAY 0.872340 (-8025 3000);
PAINT GREEN (-8025 3000);
DISPLAY INVISIBLE (-8025 3000);
FORCEPROP 2 LAST CDS_LIB mstr_standard
J 0
(-8350 3125);
DISPLAY 0.808511 (-8350 3125);
DISPLAY INVISIBLE (-8350 3125);
FORCEADD TAP..1
(-6050 2275);
FORCEPROP 3 LASTPIN (-6100 2275) SIG_NAME M_A_CPU0_SB_DQ<1>
J 0
(-6090 2285);
DISPLAY 0.659574 (-6090 2285);
PAINT MONO (-6090 2285);
DISPLAY INVISIBLE (-6090 2285);
FORCEPROP 1 LASTPIN (-6100 2275) BN 1
J 0
(-6112 2283);
DISPLAY 0.489362 (-6112 2283);
PAINT GREEN (-6112 2283);
FORCEPROP 2 LAST CDS_LIB mstr_standard
J 0
(-6050 2275);
DISPLAY 0.723404 (-6050 2275);
PAINT MONO (-6050 2275);
DISPLAY INVISIBLE (-6050 2275);
FORCEPROP 1 LAST BODY_TYPE PLUMBING
J 0
(-6050 2325);
DISPLAY 0.872340 (-6050 2325);
PAINT GREEN (-6050 2325);
DISPLAY INVISIBLE (-6050 2325);
FORCEPROP 1 LAST HDL_TAP TRUE
J 0
(-5725 2150);
DISPLAY 0.872340 (-5725 2150);
DISPLAY INVISIBLE (-5725 2150);
FORCEPROP 1 LAST PATH I383
J 0
(-6052 2275);
DISPLAY 0.872340 (-6052 2275);
PAINT GREEN (-6052 2275);
DISPLAY INVISIBLE (-6052 2275);
FORCEADD TAP..1
(-6050 2225);
FORCEPROP 3 LASTPIN (-6100 2225) SIG_NAME M_A_CPU0_SB_DQ<0>
J 0
(-6090 2235);
DISPLAY 0.659574 (-6090 2235);
PAINT MONO (-6090 2235);
DISPLAY INVISIBLE (-6090 2235);
FORCEPROP 1 LASTPIN (-6100 2225) BN 0
J 0
(-6112 2233);
DISPLAY 0.489362 (-6112 2233);
PAINT GREEN (-6112 2233);
FORCEPROP 2 LAST CDS_LIB mstr_standard
J 0
(-6050 2225);
DISPLAY 0.723404 (-6050 2225);
PAINT MONO (-6050 2225);
DISPLAY INVISIBLE (-6050 2225);
FORCEPROP 1 LAST BODY_TYPE PLUMBING
J 0
(-6050 2275);
DISPLAY 0.872340 (-6050 2275);
PAINT GREEN (-6050 2275);
DISPLAY INVISIBLE (-6050 2275);
FORCEPROP 1 LAST HDL_TAP TRUE
J 0
(-5725 2100);
DISPLAY 0.872340 (-5725 2100);
DISPLAY INVISIBLE (-5725 2100);
FORCEPROP 1 LAST PATH I384
J 0
(-6052 2225);
DISPLAY 0.872340 (-6052 2225);
PAINT GREEN (-6052 2225);
DISPLAY INVISIBLE (-6052 2225);
FORCEADD TAP..1
(-6050 2325);
FORCEPROP 3 LASTPIN (-6100 2325) SIG_NAME M_A_CPU0_SB_DQ<2>
J 0
(-6090 2335);
DISPLAY 0.659574 (-6090 2335);
PAINT MONO (-6090 2335);
DISPLAY INVISIBLE (-6090 2335);
FORCEPROP 1 LASTPIN (-6100 2325) BN 2
J 0
(-6112 2333);
DISPLAY 0.489362 (-6112 2333);
PAINT GREEN (-6112 2333);
FORCEPROP 2 LAST CDS_LIB mstr_standard
J 0
(-6050 2325);
DISPLAY 0.723404 (-6050 2325);
PAINT MONO (-6050 2325);
DISPLAY INVISIBLE (-6050 2325);
FORCEPROP 1 LAST BODY_TYPE PLUMBING
J 0
(-6050 2375);
DISPLAY 0.872340 (-6050 2375);
PAINT GREEN (-6050 2375);
DISPLAY INVISIBLE (-6050 2375);
FORCEPROP 1 LAST HDL_TAP TRUE
J 0
(-5725 2200);
DISPLAY 0.872340 (-5725 2200);
DISPLAY INVISIBLE (-5725 2200);
FORCEPROP 1 LAST PATH I385
J 0
(-6052 2325);
DISPLAY 0.872340 (-6052 2325);
PAINT GREEN (-6052 2325);
DISPLAY INVISIBLE (-6052 2325);
FORCEADD TAP..1
(-6050 2375);
FORCEPROP 3 LASTPIN (-6100 2375) SIG_NAME M_A_CPU0_SB_DQ<3>
J 0
(-6090 2385);
DISPLAY 0.659574 (-6090 2385);
PAINT MONO (-6090 2385);
DISPLAY INVISIBLE (-6090 2385);
FORCEPROP 1 LASTPIN (-6100 2375) BN 3
J 0
(-6112 2383);
DISPLAY 0.489362 (-6112 2383);
PAINT GREEN (-6112 2383);
FORCEPROP 2 LAST CDS_LIB mstr_standard
J 0
(-6050 2375);
DISPLAY 0.723404 (-6050 2375);
PAINT MONO (-6050 2375);
DISPLAY INVISIBLE (-6050 2375);
FORCEPROP 1 LAST BODY_TYPE PLUMBING
J 0
(-6050 2425);
DISPLAY 0.872340 (-6050 2425);
PAINT GREEN (-6050 2425);
DISPLAY INVISIBLE (-6050 2425);
FORCEPROP 1 LAST HDL_TAP TRUE
J 0
(-5725 2250);
DISPLAY 0.872340 (-5725 2250);
DISPLAY INVISIBLE (-5725 2250);
FORCEPROP 1 LAST PATH I386
J 0
(-6052 2375);
DISPLAY 0.872340 (-6052 2375);
PAINT GREEN (-6052 2375);
DISPLAY INVISIBLE (-6052 2375);
FORCEADD TAP..1
(-6050 2425);
FORCEPROP 3 LASTPIN (-6100 2425) SIG_NAME M_A_CPU0_SB_DQ<4>
J 0
(-6090 2435);
DISPLAY 0.659574 (-6090 2435);
PAINT MONO (-6090 2435);
DISPLAY INVISIBLE (-6090 2435);
FORCEPROP 1 LASTPIN (-6100 2425) BN 4
J 0
(-6112 2433);
DISPLAY 0.489362 (-6112 2433);
PAINT GREEN (-6112 2433);
FORCEPROP 2 LAST CDS_LIB mstr_standard
J 0
(-6050 2425);
DISPLAY 0.723404 (-6050 2425);
PAINT MONO (-6050 2425);
DISPLAY INVISIBLE (-6050 2425);
FORCEPROP 1 LAST BODY_TYPE PLUMBING
J 0
(-6050 2475);
DISPLAY 0.872340 (-6050 2475);
PAINT GREEN (-6050 2475);
DISPLAY INVISIBLE (-6050 2475);
FORCEPROP 1 LAST HDL_TAP TRUE
J 0
(-5725 2300);
DISPLAY 0.872340 (-5725 2300);
DISPLAY INVISIBLE (-5725 2300);
FORCEPROP 1 LAST PATH I387
J 0
(-6052 2425);
DISPLAY 0.872340 (-6052 2425);
PAINT GREEN (-6052 2425);
DISPLAY INVISIBLE (-6052 2425);
FORCEADD TAP..1
(-6050 2475);
FORCEPROP 3 LASTPIN (-6100 2475) SIG_NAME M_A_CPU0_SB_DQ<5>
J 0
(-6090 2485);
DISPLAY 0.659574 (-6090 2485);
PAINT MONO (-6090 2485);
DISPLAY INVISIBLE (-6090 2485);
FORCEPROP 1 LASTPIN (-6100 2475) BN 5
J 0
(-6112 2483);
DISPLAY 0.489362 (-6112 2483);
PAINT GREEN (-6112 2483);
FORCEPROP 2 LAST CDS_LIB mstr_standard
J 0
(-6050 2475);
DISPLAY 0.723404 (-6050 2475);
PAINT MONO (-6050 2475);
DISPLAY INVISIBLE (-6050 2475);
FORCEPROP 1 LAST BODY_TYPE PLUMBING
J 0
(-6050 2525);
DISPLAY 0.872340 (-6050 2525);
PAINT GREEN (-6050 2525);
DISPLAY INVISIBLE (-6050 2525);
FORCEPROP 1 LAST HDL_TAP TRUE
J 0
(-5725 2350);
DISPLAY 0.872340 (-5725 2350);
DISPLAY INVISIBLE (-5725 2350);
FORCEPROP 1 LAST PATH I388
J 0
(-6052 2475);
DISPLAY 0.872340 (-6052 2475);
PAINT GREEN (-6052 2475);
DISPLAY INVISIBLE (-6052 2475);
FORCEADD TAP..1
(-6050 2525);
FORCEPROP 3 LASTPIN (-6100 2525) SIG_NAME M_A_CPU0_SB_DQ<6>
J 0
(-6090 2535);
DISPLAY 0.659574 (-6090 2535);
PAINT MONO (-6090 2535);
DISPLAY INVISIBLE (-6090 2535);
FORCEPROP 1 LASTPIN (-6100 2525) BN 6
J 0
(-6112 2533);
DISPLAY 0.489362 (-6112 2533);
PAINT GREEN (-6112 2533);
FORCEPROP 2 LAST CDS_LIB mstr_standard
J 0
(-6050 2525);
DISPLAY 0.723404 (-6050 2525);
PAINT MONO (-6050 2525);
DISPLAY INVISIBLE (-6050 2525);
FORCEPROP 1 LAST BODY_TYPE PLUMBING
J 0
(-6050 2575);
DISPLAY 0.872340 (-6050 2575);
PAINT GREEN (-6050 2575);
DISPLAY INVISIBLE (-6050 2575);
FORCEPROP 1 LAST HDL_TAP TRUE
J 0
(-5725 2400);
DISPLAY 0.872340 (-5725 2400);
DISPLAY INVISIBLE (-5725 2400);
FORCEPROP 1 LAST PATH I389
J 0
(-6052 2525);
DISPLAY 0.872340 (-6052 2525);
PAINT GREEN (-6052 2525);
DISPLAY INVISIBLE (-6052 2525);
FORCEADD TAP..1
(-6050 2575);
FORCEPROP 3 LASTPIN (-6100 2575) SIG_NAME M_A_CPU0_SB_DQ<7>
J 0
(-6090 2585);
DISPLAY 0.659574 (-6090 2585);
PAINT MONO (-6090 2585);
DISPLAY INVISIBLE (-6090 2585);
FORCEPROP 1 LASTPIN (-6100 2575) BN 7
J 0
(-6112 2583);
DISPLAY 0.489362 (-6112 2583);
PAINT GREEN (-6112 2583);
FORCEPROP 2 LAST CDS_LIB mstr_standard
J 0
(-6050 2575);
DISPLAY 0.723404 (-6050 2575);
PAINT MONO (-6050 2575);
DISPLAY INVISIBLE (-6050 2575);
FORCEPROP 1 LAST BODY_TYPE PLUMBING
J 0
(-6050 2625);
DISPLAY 0.872340 (-6050 2625);
PAINT GREEN (-6050 2625);
DISPLAY INVISIBLE (-6050 2625);
FORCEPROP 1 LAST HDL_TAP TRUE
J 0
(-5725 2450);
DISPLAY 0.872340 (-5725 2450);
DISPLAY INVISIBLE (-5725 2450);
FORCEPROP 1 LAST PATH I390
J 0
(-6052 2575);
DISPLAY 0.872340 (-6052 2575);
PAINT GREEN (-6052 2575);
DISPLAY INVISIBLE (-6052 2575);
FORCEADD TAP..1
(-6050 2625);
FORCEPROP 3 LASTPIN (-6100 2625) SIG_NAME M_A_CPU0_SB_DQ<8>
J 0
(-6090 2635);
DISPLAY 0.659574 (-6090 2635);
PAINT MONO (-6090 2635);
DISPLAY INVISIBLE (-6090 2635);
FORCEPROP 1 LASTPIN (-6100 2625) BN 8
J 0
(-6112 2633);
DISPLAY 0.489362 (-6112 2633);
PAINT GREEN (-6112 2633);
FORCEPROP 2 LAST CDS_LIB mstr_standard
J 0
(-6050 2625);
DISPLAY 0.723404 (-6050 2625);
PAINT MONO (-6050 2625);
DISPLAY INVISIBLE (-6050 2625);
FORCEPROP 1 LAST BODY_TYPE PLUMBING
J 0
(-6050 2675);
DISPLAY 0.872340 (-6050 2675);
PAINT GREEN (-6050 2675);
DISPLAY INVISIBLE (-6050 2675);
FORCEPROP 1 LAST HDL_TAP TRUE
J 0
(-5725 2500);
DISPLAY 0.872340 (-5725 2500);
DISPLAY INVISIBLE (-5725 2500);
FORCEPROP 1 LAST PATH I391
J 0
(-6052 2625);
DISPLAY 0.872340 (-6052 2625);
PAINT GREEN (-6052 2625);
DISPLAY INVISIBLE (-6052 2625);
FORCEADD TAP..1
(-6050 2675);
FORCEPROP 3 LASTPIN (-6100 2675) SIG_NAME M_A_CPU0_SB_DQ<9>
J 0
(-6090 2685);
DISPLAY 0.659574 (-6090 2685);
PAINT MONO (-6090 2685);
DISPLAY INVISIBLE (-6090 2685);
FORCEPROP 1 LASTPIN (-6100 2675) BN 9
J 0
(-6112 2683);
DISPLAY 0.489362 (-6112 2683);
PAINT GREEN (-6112 2683);
FORCEPROP 2 LAST CDS_LIB mstr_standard
J 0
(-6050 2675);
DISPLAY 0.723404 (-6050 2675);
PAINT MONO (-6050 2675);
DISPLAY INVISIBLE (-6050 2675);
FORCEPROP 1 LAST BODY_TYPE PLUMBING
J 0
(-6050 2725);
DISPLAY 0.872340 (-6050 2725);
PAINT GREEN (-6050 2725);
DISPLAY INVISIBLE (-6050 2725);
FORCEPROP 1 LAST HDL_TAP TRUE
J 0
(-5725 2550);
DISPLAY 0.872340 (-5725 2550);
DISPLAY INVISIBLE (-5725 2550);
FORCEPROP 1 LAST PATH I392
J 0
(-6052 2675);
DISPLAY 0.872340 (-6052 2675);
PAINT GREEN (-6052 2675);
DISPLAY INVISIBLE (-6052 2675);
FORCEADD TAP..1
(-6050 2725);
FORCEPROP 3 LASTPIN (-6100 2725) SIG_NAME M_A_CPU0_SB_DQ<10>
J 0
(-6090 2735);
DISPLAY 0.659574 (-6090 2735);
PAINT MONO (-6090 2735);
DISPLAY INVISIBLE (-6090 2735);
FORCEPROP 1 LASTPIN (-6100 2725) BN 10
J 0
(-6112 2733);
DISPLAY 0.489362 (-6112 2733);
PAINT GREEN (-6112 2733);
FORCEPROP 2 LAST CDS_LIB mstr_standard
J 0
(-6050 2725);
DISPLAY 0.723404 (-6050 2725);
PAINT MONO (-6050 2725);
DISPLAY INVISIBLE (-6050 2725);
FORCEPROP 1 LAST BODY_TYPE PLUMBING
J 0
(-6050 2775);
DISPLAY 0.872340 (-6050 2775);
PAINT GREEN (-6050 2775);
DISPLAY INVISIBLE (-6050 2775);
FORCEPROP 1 LAST HDL_TAP TRUE
J 0
(-5725 2600);
DISPLAY 0.872340 (-5725 2600);
DISPLAY INVISIBLE (-5725 2600);
FORCEPROP 1 LAST PATH I393
J 0
(-6052 2725);
DISPLAY 0.872340 (-6052 2725);
PAINT GREEN (-6052 2725);
DISPLAY INVISIBLE (-6052 2725);
FORCEADD TAP..1
(-6050 2825);
FORCEPROP 3 LASTPIN (-6100 2825) SIG_NAME M_A_CPU0_SB_DQ<12>
J 0
(-6090 2835);
DISPLAY 0.659574 (-6090 2835);
PAINT MONO (-6090 2835);
DISPLAY INVISIBLE (-6090 2835);
FORCEPROP 1 LASTPIN (-6100 2825) BN 12
J 0
(-6112 2833);
DISPLAY 0.489362 (-6112 2833);
PAINT GREEN (-6112 2833);
FORCEPROP 2 LAST CDS_LIB mstr_standard
J 0
(-6050 2825);
DISPLAY 0.723404 (-6050 2825);
PAINT MONO (-6050 2825);
DISPLAY INVISIBLE (-6050 2825);
FORCEPROP 1 LAST BODY_TYPE PLUMBING
J 0
(-6050 2875);
DISPLAY 0.872340 (-6050 2875);
PAINT GREEN (-6050 2875);
DISPLAY INVISIBLE (-6050 2875);
FORCEPROP 1 LAST HDL_TAP TRUE
J 0
(-5725 2700);
DISPLAY 0.872340 (-5725 2700);
DISPLAY INVISIBLE (-5725 2700);
FORCEPROP 1 LAST PATH I394
J 0
(-6052 2825);
DISPLAY 0.872340 (-6052 2825);
PAINT GREEN (-6052 2825);
DISPLAY INVISIBLE (-6052 2825);
FORCEADD TAP..1
(-6050 2775);
FORCEPROP 3 LASTPIN (-6100 2775) SIG_NAME M_A_CPU0_SB_DQ<11>
J 0
(-6090 2785);
DISPLAY 0.659574 (-6090 2785);
PAINT MONO (-6090 2785);
DISPLAY INVISIBLE (-6090 2785);
FORCEPROP 1 LASTPIN (-6100 2775) BN 11
J 0
(-6112 2783);
DISPLAY 0.489362 (-6112 2783);
PAINT GREEN (-6112 2783);
FORCEPROP 2 LAST CDS_LIB mstr_standard
J 0
(-6050 2775);
DISPLAY 0.723404 (-6050 2775);
PAINT MONO (-6050 2775);
DISPLAY INVISIBLE (-6050 2775);
FORCEPROP 1 LAST BODY_TYPE PLUMBING
J 0
(-6050 2825);
DISPLAY 0.872340 (-6050 2825);
PAINT GREEN (-6050 2825);
DISPLAY INVISIBLE (-6050 2825);
FORCEPROP 1 LAST HDL_TAP TRUE
J 0
(-5725 2650);
DISPLAY 0.872340 (-5725 2650);
DISPLAY INVISIBLE (-5725 2650);
FORCEPROP 1 LAST PATH I395
J 0
(-6052 2775);
DISPLAY 0.872340 (-6052 2775);
PAINT GREEN (-6052 2775);
DISPLAY INVISIBLE (-6052 2775);
FORCEADD TAP..1
(-6050 2875);
FORCEPROP 3 LASTPIN (-6100 2875) SIG_NAME M_A_CPU0_SB_DQ<13>
J 0
(-6090 2885);
DISPLAY 0.659574 (-6090 2885);
PAINT MONO (-6090 2885);
DISPLAY INVISIBLE (-6090 2885);
FORCEPROP 1 LASTPIN (-6100 2875) BN 13
J 0
(-6112 2883);
DISPLAY 0.489362 (-6112 2883);
PAINT GREEN (-6112 2883);
FORCEPROP 2 LAST CDS_LIB mstr_standard
J 0
(-6050 2875);
DISPLAY 0.723404 (-6050 2875);
PAINT MONO (-6050 2875);
DISPLAY INVISIBLE (-6050 2875);
FORCEPROP 1 LAST BODY_TYPE PLUMBING
J 0
(-6050 2925);
DISPLAY 0.872340 (-6050 2925);
PAINT GREEN (-6050 2925);
DISPLAY INVISIBLE (-6050 2925);
FORCEPROP 1 LAST HDL_TAP TRUE
J 0
(-5725 2750);
DISPLAY 0.872340 (-5725 2750);
DISPLAY INVISIBLE (-5725 2750);
FORCEPROP 1 LAST PATH I396
J 0
(-6052 2875);
DISPLAY 0.872340 (-6052 2875);
PAINT GREEN (-6052 2875);
DISPLAY INVISIBLE (-6052 2875);
FORCEADD TAP..1
(-6050 2975);
FORCEPROP 3 LASTPIN (-6100 2975) SIG_NAME M_A_CPU0_SB_DQ<15>
J 0
(-6090 2985);
DISPLAY 0.659574 (-6090 2985);
PAINT MONO (-6090 2985);
DISPLAY INVISIBLE (-6090 2985);
FORCEPROP 1 LASTPIN (-6100 2975) BN 15
J 0
(-6112 2983);
DISPLAY 0.489362 (-6112 2983);
PAINT GREEN (-6112 2983);
FORCEPROP 2 LAST CDS_LIB mstr_standard
J 0
(-6050 2975);
DISPLAY 0.723404 (-6050 2975);
PAINT MONO (-6050 2975);
DISPLAY INVISIBLE (-6050 2975);
FORCEPROP 1 LAST BODY_TYPE PLUMBING
J 0
(-6050 3025);
DISPLAY 0.872340 (-6050 3025);
PAINT GREEN (-6050 3025);
DISPLAY INVISIBLE (-6050 3025);
FORCEPROP 1 LAST HDL_TAP TRUE
J 0
(-5725 2850);
DISPLAY 0.872340 (-5725 2850);
DISPLAY INVISIBLE (-5725 2850);
FORCEPROP 1 LAST PATH I397
J 0
(-6052 2975);
DISPLAY 0.872340 (-6052 2975);
PAINT GREEN (-6052 2975);
DISPLAY INVISIBLE (-6052 2975);
FORCEADD TAP..1
(-6050 2925);
FORCEPROP 3 LASTPIN (-6100 2925) SIG_NAME M_A_CPU0_SB_DQ<14>
J 0
(-6090 2935);
DISPLAY 0.659574 (-6090 2935);
PAINT MONO (-6090 2935);
DISPLAY INVISIBLE (-6090 2935);
FORCEPROP 1 LASTPIN (-6100 2925) BN 14
J 0
(-6112 2933);
DISPLAY 0.489362 (-6112 2933);
PAINT GREEN (-6112 2933);
FORCEPROP 2 LAST CDS_LIB mstr_standard
J 0
(-6050 2925);
DISPLAY 0.723404 (-6050 2925);
PAINT MONO (-6050 2925);
DISPLAY INVISIBLE (-6050 2925);
FORCEPROP 1 LAST BODY_TYPE PLUMBING
J 0
(-6050 2975);
DISPLAY 0.872340 (-6050 2975);
PAINT GREEN (-6050 2975);
DISPLAY INVISIBLE (-6050 2975);
FORCEPROP 1 LAST HDL_TAP TRUE
J 0
(-5725 2800);
DISPLAY 0.872340 (-5725 2800);
DISPLAY INVISIBLE (-5725 2800);
FORCEPROP 1 LAST PATH I398
J 0
(-6052 2925);
DISPLAY 0.872340 (-6052 2925);
PAINT GREEN (-6052 2925);
DISPLAY INVISIBLE (-6052 2925);
FORCEADD TAP..1
(-6050 3025);
FORCEPROP 3 LASTPIN (-6100 3025) SIG_NAME M_A_CPU0_SB_DQ<16>
J 0
(-6090 3035);
DISPLAY 0.659574 (-6090 3035);
PAINT MONO (-6090 3035);
DISPLAY INVISIBLE (-6090 3035);
FORCEPROP 1 LASTPIN (-6100 3025) BN 16
J 0
(-6112 3033);
DISPLAY 0.489362 (-6112 3033);
PAINT GREEN (-6112 3033);
FORCEPROP 2 LAST CDS_LIB mstr_standard
J 0
(-6050 3025);
DISPLAY 0.723404 (-6050 3025);
PAINT MONO (-6050 3025);
DISPLAY INVISIBLE (-6050 3025);
FORCEPROP 1 LAST BODY_TYPE PLUMBING
J 0
(-6050 3075);
DISPLAY 0.872340 (-6050 3075);
PAINT GREEN (-6050 3075);
DISPLAY INVISIBLE (-6050 3075);
FORCEPROP 1 LAST HDL_TAP TRUE
J 0
(-5725 2900);
DISPLAY 0.872340 (-5725 2900);
DISPLAY INVISIBLE (-5725 2900);
FORCEPROP 1 LAST PATH I399
J 0
(-6052 3025);
DISPLAY 0.872340 (-6052 3025);
PAINT GREEN (-6052 3025);
DISPLAY INVISIBLE (-6052 3025);
FORCEADD TAP..1
(-6050 3075);
FORCEPROP 3 LASTPIN (-6100 3075) SIG_NAME M_A_CPU0_SB_DQ<17>
J 0
(-6090 3085);
DISPLAY 0.659574 (-6090 3085);
PAINT MONO (-6090 3085);
DISPLAY INVISIBLE (-6090 3085);
FORCEPROP 1 LASTPIN (-6100 3075) BN 17
J 0
(-6112 3083);
DISPLAY 0.489362 (-6112 3083);
PAINT GREEN (-6112 3083);
FORCEPROP 2 LAST CDS_LIB mstr_standard
J 0
(-6050 3075);
DISPLAY 0.723404 (-6050 3075);
PAINT MONO (-6050 3075);
DISPLAY INVISIBLE (-6050 3075);
FORCEPROP 1 LAST BODY_TYPE PLUMBING
J 0
(-6050 3125);
DISPLAY 0.872340 (-6050 3125);
PAINT GREEN (-6050 3125);
DISPLAY INVISIBLE (-6050 3125);
FORCEPROP 1 LAST HDL_TAP TRUE
J 0
(-5725 2950);
DISPLAY 0.872340 (-5725 2950);
DISPLAY INVISIBLE (-5725 2950);
FORCEPROP 1 LAST PATH I400
J 0
(-6052 3075);
DISPLAY 0.872340 (-6052 3075);
PAINT GREEN (-6052 3075);
DISPLAY INVISIBLE (-6052 3075);
FORCEADD TAP..1
(-6050 3125);
FORCEPROP 3 LASTPIN (-6100 3125) SIG_NAME M_A_CPU0_SB_DQ<18>
J 0
(-6090 3135);
DISPLAY 0.659574 (-6090 3135);
PAINT MONO (-6090 3135);
DISPLAY INVISIBLE (-6090 3135);
FORCEPROP 1 LASTPIN (-6100 3125) BN 18
J 0
(-6112 3133);
DISPLAY 0.489362 (-6112 3133);
PAINT GREEN (-6112 3133);
FORCEPROP 2 LAST CDS_LIB mstr_standard
J 0
(-6050 3125);
DISPLAY 0.723404 (-6050 3125);
PAINT MONO (-6050 3125);
DISPLAY INVISIBLE (-6050 3125);
FORCEPROP 1 LAST BODY_TYPE PLUMBING
J 0
(-6050 3175);
DISPLAY 0.872340 (-6050 3175);
PAINT GREEN (-6050 3175);
DISPLAY INVISIBLE (-6050 3175);
FORCEPROP 1 LAST HDL_TAP TRUE
J 0
(-5725 3000);
DISPLAY 0.872340 (-5725 3000);
DISPLAY INVISIBLE (-5725 3000);
FORCEPROP 1 LAST PATH I401
J 0
(-6052 3125);
DISPLAY 0.872340 (-6052 3125);
PAINT GREEN (-6052 3125);
DISPLAY INVISIBLE (-6052 3125);
FORCEADD TAP..1
(-6050 3175);
FORCEPROP 3 LASTPIN (-6100 3175) SIG_NAME M_A_CPU0_SB_DQ<19>
J 0
(-6090 3185);
DISPLAY 0.659574 (-6090 3185);
PAINT MONO (-6090 3185);
DISPLAY INVISIBLE (-6090 3185);
FORCEPROP 1 LASTPIN (-6100 3175) BN 19
J 0
(-6112 3183);
DISPLAY 0.489362 (-6112 3183);
PAINT GREEN (-6112 3183);
FORCEPROP 2 LAST CDS_LIB mstr_standard
J 0
(-6050 3175);
DISPLAY 0.723404 (-6050 3175);
PAINT MONO (-6050 3175);
DISPLAY INVISIBLE (-6050 3175);
FORCEPROP 1 LAST BODY_TYPE PLUMBING
J 0
(-6050 3225);
DISPLAY 0.872340 (-6050 3225);
PAINT GREEN (-6050 3225);
DISPLAY INVISIBLE (-6050 3225);
FORCEPROP 1 LAST HDL_TAP TRUE
J 0
(-5725 3050);
DISPLAY 0.872340 (-5725 3050);
DISPLAY INVISIBLE (-5725 3050);
FORCEPROP 1 LAST PATH I402
J 0
(-6052 3175);
DISPLAY 0.872340 (-6052 3175);
PAINT GREEN (-6052 3175);
DISPLAY INVISIBLE (-6052 3175);
FORCEADD TAP..1
(-6050 3375);
FORCEPROP 3 LASTPIN (-6100 3375) SIG_NAME M_A_CPU0_SB_DQ<23>
J 0
(-6090 3385);
DISPLAY 0.659574 (-6090 3385);
PAINT MONO (-6090 3385);
DISPLAY INVISIBLE (-6090 3385);
FORCEPROP 1 LASTPIN (-6100 3375) BN 23
J 0
(-6112 3383);
DISPLAY 0.489362 (-6112 3383);
PAINT GREEN (-6112 3383);
FORCEPROP 2 LAST CDS_LIB mstr_standard
J 0
(-6050 3375);
DISPLAY 0.723404 (-6050 3375);
PAINT MONO (-6050 3375);
DISPLAY INVISIBLE (-6050 3375);
FORCEPROP 1 LAST BODY_TYPE PLUMBING
J 0
(-6050 3425);
DISPLAY 0.872340 (-6050 3425);
PAINT GREEN (-6050 3425);
DISPLAY INVISIBLE (-6050 3425);
FORCEPROP 1 LAST HDL_TAP TRUE
J 0
(-5725 3250);
DISPLAY 0.872340 (-5725 3250);
DISPLAY INVISIBLE (-5725 3250);
FORCEPROP 1 LAST PATH I403
J 0
(-6052 3375);
DISPLAY 0.872340 (-6052 3375);
PAINT GREEN (-6052 3375);
DISPLAY INVISIBLE (-6052 3375);
FORCEADD TAP..1
(-6050 3225);
FORCEPROP 3 LASTPIN (-6100 3225) SIG_NAME M_A_CPU0_SB_DQ<20>
J 0
(-6090 3235);
DISPLAY 0.659574 (-6090 3235);
PAINT MONO (-6090 3235);
DISPLAY INVISIBLE (-6090 3235);
FORCEPROP 1 LASTPIN (-6100 3225) BN 20
J 0
(-6112 3233);
DISPLAY 0.489362 (-6112 3233);
PAINT GREEN (-6112 3233);
FORCEPROP 2 LAST CDS_LIB mstr_standard
J 0
(-6050 3225);
DISPLAY 0.723404 (-6050 3225);
PAINT MONO (-6050 3225);
DISPLAY INVISIBLE (-6050 3225);
FORCEPROP 1 LAST BODY_TYPE PLUMBING
J 0
(-6050 3275);
DISPLAY 0.872340 (-6050 3275);
PAINT GREEN (-6050 3275);
DISPLAY INVISIBLE (-6050 3275);
FORCEPROP 1 LAST HDL_TAP TRUE
J 0
(-5725 3100);
DISPLAY 0.872340 (-5725 3100);
DISPLAY INVISIBLE (-5725 3100);
FORCEPROP 1 LAST PATH I404
J 0
(-6052 3225);
DISPLAY 0.872340 (-6052 3225);
PAINT GREEN (-6052 3225);
DISPLAY INVISIBLE (-6052 3225);
FORCEADD TAP..1
(-6050 3275);
FORCEPROP 3 LASTPIN (-6100 3275) SIG_NAME M_A_CPU0_SB_DQ<21>
J 0
(-6090 3285);
DISPLAY 0.659574 (-6090 3285);
PAINT MONO (-6090 3285);
DISPLAY INVISIBLE (-6090 3285);
FORCEPROP 1 LASTPIN (-6100 3275) BN 21
J 0
(-6112 3283);
DISPLAY 0.489362 (-6112 3283);
PAINT GREEN (-6112 3283);
FORCEPROP 2 LAST CDS_LIB mstr_standard
J 0
(-6050 3275);
DISPLAY 0.723404 (-6050 3275);
PAINT MONO (-6050 3275);
DISPLAY INVISIBLE (-6050 3275);
FORCEPROP 1 LAST BODY_TYPE PLUMBING
J 0
(-6050 3325);
DISPLAY 0.872340 (-6050 3325);
PAINT GREEN (-6050 3325);
DISPLAY INVISIBLE (-6050 3325);
FORCEPROP 1 LAST HDL_TAP TRUE
J 0
(-5725 3150);
DISPLAY 0.872340 (-5725 3150);
DISPLAY INVISIBLE (-5725 3150);
FORCEPROP 1 LAST PATH I405
J 0
(-6052 3275);
DISPLAY 0.872340 (-6052 3275);
PAINT GREEN (-6052 3275);
DISPLAY INVISIBLE (-6052 3275);
FORCEADD TAP..1
(-6050 3325);
FORCEPROP 3 LASTPIN (-6100 3325) SIG_NAME M_A_CPU0_SB_DQ<22>
J 0
(-6090 3335);
DISPLAY 0.659574 (-6090 3335);
PAINT MONO (-6090 3335);
DISPLAY INVISIBLE (-6090 3335);
FORCEPROP 1 LASTPIN (-6100 3325) BN 22
J 0
(-6112 3333);
DISPLAY 0.489362 (-6112 3333);
PAINT GREEN (-6112 3333);
FORCEPROP 2 LAST CDS_LIB mstr_standard
J 0
(-6050 3325);
DISPLAY 0.723404 (-6050 3325);
PAINT MONO (-6050 3325);
DISPLAY INVISIBLE (-6050 3325);
FORCEPROP 1 LAST BODY_TYPE PLUMBING
J 0
(-6050 3375);
DISPLAY 0.872340 (-6050 3375);
PAINT GREEN (-6050 3375);
DISPLAY INVISIBLE (-6050 3375);
FORCEPROP 1 LAST HDL_TAP TRUE
J 0
(-5725 3200);
DISPLAY 0.872340 (-5725 3200);
DISPLAY INVISIBLE (-5725 3200);
FORCEPROP 1 LAST PATH I406
J 0
(-6052 3325);
DISPLAY 0.872340 (-6052 3325);
PAINT GREEN (-6052 3325);
DISPLAY INVISIBLE (-6052 3325);
FORCEADD TAP..1
(-6050 3425);
FORCEPROP 3 LASTPIN (-6100 3425) SIG_NAME M_A_CPU0_SB_DQ<24>
J 0
(-6090 3435);
DISPLAY 0.659574 (-6090 3435);
PAINT MONO (-6090 3435);
DISPLAY INVISIBLE (-6090 3435);
FORCEPROP 1 LASTPIN (-6100 3425) BN 24
J 0
(-6112 3433);
DISPLAY 0.489362 (-6112 3433);
PAINT GREEN (-6112 3433);
FORCEPROP 2 LAST CDS_LIB mstr_standard
J 0
(-6050 3425);
DISPLAY 0.723404 (-6050 3425);
PAINT MONO (-6050 3425);
DISPLAY INVISIBLE (-6050 3425);
FORCEPROP 1 LAST BODY_TYPE PLUMBING
J 0
(-6050 3475);
DISPLAY 0.872340 (-6050 3475);
PAINT GREEN (-6050 3475);
DISPLAY INVISIBLE (-6050 3475);
FORCEPROP 1 LAST HDL_TAP TRUE
J 0
(-5725 3300);
DISPLAY 0.872340 (-5725 3300);
DISPLAY INVISIBLE (-5725 3300);
FORCEPROP 1 LAST PATH I407
J 0
(-6052 3425);
DISPLAY 0.872340 (-6052 3425);
PAINT GREEN (-6052 3425);
DISPLAY INVISIBLE (-6052 3425);
FORCEADD TAP..1
(-6050 3625);
FORCEPROP 3 LASTPIN (-6100 3625) SIG_NAME M_A_CPU0_SB_DQ<28>
J 0
(-6090 3635);
DISPLAY 0.659574 (-6090 3635);
PAINT MONO (-6090 3635);
DISPLAY INVISIBLE (-6090 3635);
FORCEPROP 1 LASTPIN (-6100 3625) BN 28
J 0
(-6112 3633);
DISPLAY 0.489362 (-6112 3633);
PAINT GREEN (-6112 3633);
FORCEPROP 2 LAST CDS_LIB mstr_standard
J 0
(-6050 3625);
DISPLAY 0.723404 (-6050 3625);
PAINT MONO (-6050 3625);
DISPLAY INVISIBLE (-6050 3625);
FORCEPROP 1 LAST BODY_TYPE PLUMBING
J 0
(-6050 3675);
DISPLAY 0.872340 (-6050 3675);
PAINT GREEN (-6050 3675);
DISPLAY INVISIBLE (-6050 3675);
FORCEPROP 1 LAST HDL_TAP TRUE
J 0
(-5725 3500);
DISPLAY 0.872340 (-5725 3500);
DISPLAY INVISIBLE (-5725 3500);
FORCEPROP 1 LAST PATH I408
J 0
(-6052 3625);
DISPLAY 0.872340 (-6052 3625);
PAINT GREEN (-6052 3625);
DISPLAY INVISIBLE (-6052 3625);
FORCEADD TAP..1
(-6050 3475);
FORCEPROP 3 LASTPIN (-6100 3475) SIG_NAME M_A_CPU0_SB_DQ<25>
J 0
(-6090 3485);
DISPLAY 0.659574 (-6090 3485);
PAINT MONO (-6090 3485);
DISPLAY INVISIBLE (-6090 3485);
FORCEPROP 1 LASTPIN (-6100 3475) BN 25
J 0
(-6112 3483);
DISPLAY 0.489362 (-6112 3483);
PAINT GREEN (-6112 3483);
FORCEPROP 2 LAST CDS_LIB mstr_standard
J 0
(-6050 3475);
DISPLAY 0.723404 (-6050 3475);
PAINT MONO (-6050 3475);
DISPLAY INVISIBLE (-6050 3475);
FORCEPROP 1 LAST BODY_TYPE PLUMBING
J 0
(-6050 3525);
DISPLAY 0.872340 (-6050 3525);
PAINT GREEN (-6050 3525);
DISPLAY INVISIBLE (-6050 3525);
FORCEPROP 1 LAST HDL_TAP TRUE
J 0
(-5725 3350);
DISPLAY 0.872340 (-5725 3350);
DISPLAY INVISIBLE (-5725 3350);
FORCEPROP 1 LAST PATH I409
J 0
(-6052 3475);
DISPLAY 0.872340 (-6052 3475);
PAINT GREEN (-6052 3475);
DISPLAY INVISIBLE (-6052 3475);
FORCEADD TAP..1
(-6050 3525);
FORCEPROP 3 LASTPIN (-6100 3525) SIG_NAME M_A_CPU0_SB_DQ<26>
J 0
(-6090 3535);
DISPLAY 0.659574 (-6090 3535);
PAINT MONO (-6090 3535);
DISPLAY INVISIBLE (-6090 3535);
FORCEPROP 1 LASTPIN (-6100 3525) BN 26
J 0
(-6112 3533);
DISPLAY 0.489362 (-6112 3533);
PAINT GREEN (-6112 3533);
FORCEPROP 2 LAST CDS_LIB mstr_standard
J 0
(-6050 3525);
DISPLAY 0.723404 (-6050 3525);
PAINT MONO (-6050 3525);
DISPLAY INVISIBLE (-6050 3525);
FORCEPROP 1 LAST BODY_TYPE PLUMBING
J 0
(-6050 3575);
DISPLAY 0.872340 (-6050 3575);
PAINT GREEN (-6050 3575);
DISPLAY INVISIBLE (-6050 3575);
FORCEPROP 1 LAST HDL_TAP TRUE
J 0
(-5725 3400);
DISPLAY 0.872340 (-5725 3400);
DISPLAY INVISIBLE (-5725 3400);
FORCEPROP 1 LAST PATH I410
J 0
(-6052 3525);
DISPLAY 0.872340 (-6052 3525);
PAINT GREEN (-6052 3525);
DISPLAY INVISIBLE (-6052 3525);
FORCEADD TAP..1
(-6050 3575);
FORCEPROP 3 LASTPIN (-6100 3575) SIG_NAME M_A_CPU0_SB_DQ<27>
J 0
(-6090 3585);
DISPLAY 0.659574 (-6090 3585);
PAINT MONO (-6090 3585);
DISPLAY INVISIBLE (-6090 3585);
FORCEPROP 1 LASTPIN (-6100 3575) BN 27
J 0
(-6112 3583);
DISPLAY 0.489362 (-6112 3583);
PAINT GREEN (-6112 3583);
FORCEPROP 2 LAST CDS_LIB mstr_standard
J 0
(-6050 3575);
DISPLAY 0.723404 (-6050 3575);
PAINT MONO (-6050 3575);
DISPLAY INVISIBLE (-6050 3575);
FORCEPROP 1 LAST BODY_TYPE PLUMBING
J 0
(-6050 3625);
DISPLAY 0.872340 (-6050 3625);
PAINT GREEN (-6050 3625);
DISPLAY INVISIBLE (-6050 3625);
FORCEPROP 1 LAST HDL_TAP TRUE
J 0
(-5725 3450);
DISPLAY 0.872340 (-5725 3450);
DISPLAY INVISIBLE (-5725 3450);
FORCEPROP 1 LAST PATH I411
J 0
(-6052 3575);
DISPLAY 0.872340 (-6052 3575);
PAINT GREEN (-6052 3575);
DISPLAY INVISIBLE (-6052 3575);
FORCEADD TAP..1
(-6050 3675);
FORCEPROP 3 LASTPIN (-6100 3675) SIG_NAME M_A_CPU0_SB_DQ<29>
J 0
(-6090 3685);
DISPLAY 0.659574 (-6090 3685);
PAINT MONO (-6090 3685);
DISPLAY INVISIBLE (-6090 3685);
FORCEPROP 1 LASTPIN (-6100 3675) BN 29
J 0
(-6112 3683);
DISPLAY 0.489362 (-6112 3683);
PAINT GREEN (-6112 3683);
FORCEPROP 2 LAST CDS_LIB mstr_standard
J 0
(-6050 3675);
DISPLAY 0.723404 (-6050 3675);
PAINT MONO (-6050 3675);
DISPLAY INVISIBLE (-6050 3675);
FORCEPROP 1 LAST BODY_TYPE PLUMBING
J 0
(-6050 3725);
DISPLAY 0.872340 (-6050 3725);
PAINT GREEN (-6050 3725);
DISPLAY INVISIBLE (-6050 3725);
FORCEPROP 1 LAST HDL_TAP TRUE
J 0
(-5725 3550);
DISPLAY 0.872340 (-5725 3550);
DISPLAY INVISIBLE (-5725 3550);
FORCEPROP 1 LAST PATH I412
J 0
(-6052 3675);
DISPLAY 0.872340 (-6052 3675);
PAINT GREEN (-6052 3675);
DISPLAY INVISIBLE (-6052 3675);
FORCEADD TAP..1
(-6050 3875);
FORCEPROP 3 LASTPIN (-6100 3875) SIG_NAME M_A_CPU0_SA_DQ<0>
J 0
(-6090 3885);
DISPLAY 0.659574 (-6090 3885);
PAINT MONO (-6090 3885);
DISPLAY INVISIBLE (-6090 3885);
FORCEPROP 1 LASTPIN (-6100 3875) BN 0
J 0
(-6112 3883);
DISPLAY 0.489362 (-6112 3883);
PAINT GREEN (-6112 3883);
FORCEPROP 2 LAST CDS_LIB mstr_standard
J 0
(-6050 3875);
DISPLAY 0.723404 (-6050 3875);
PAINT MONO (-6050 3875);
DISPLAY INVISIBLE (-6050 3875);
FORCEPROP 1 LAST BODY_TYPE PLUMBING
J 0
(-6050 3925);
DISPLAY 0.872340 (-6050 3925);
PAINT GREEN (-6050 3925);
DISPLAY INVISIBLE (-6050 3925);
FORCEPROP 1 LAST HDL_TAP TRUE
J 0
(-5725 3750);
DISPLAY 0.872340 (-5725 3750);
DISPLAY INVISIBLE (-5725 3750);
FORCEPROP 1 LAST PATH I413
J 0
(-6052 3875);
DISPLAY 0.872340 (-6052 3875);
PAINT GREEN (-6052 3875);
DISPLAY INVISIBLE (-6052 3875);
FORCEADD TAP..1
(-6050 3725);
FORCEPROP 3 LASTPIN (-6100 3725) SIG_NAME M_A_CPU0_SB_DQ<30>
J 0
(-6090 3735);
DISPLAY 0.659574 (-6090 3735);
PAINT MONO (-6090 3735);
DISPLAY INVISIBLE (-6090 3735);
FORCEPROP 1 LASTPIN (-6100 3725) BN 30
J 0
(-6112 3733);
DISPLAY 0.489362 (-6112 3733);
PAINT GREEN (-6112 3733);
FORCEPROP 2 LAST CDS_LIB mstr_standard
J 0
(-6050 3725);
DISPLAY 0.723404 (-6050 3725);
PAINT MONO (-6050 3725);
DISPLAY INVISIBLE (-6050 3725);
FORCEPROP 1 LAST BODY_TYPE PLUMBING
J 0
(-6050 3775);
DISPLAY 0.872340 (-6050 3775);
PAINT GREEN (-6050 3775);
DISPLAY INVISIBLE (-6050 3775);
FORCEPROP 1 LAST HDL_TAP TRUE
J 0
(-5725 3600);
DISPLAY 0.872340 (-5725 3600);
DISPLAY INVISIBLE (-5725 3600);
FORCEPROP 1 LAST PATH I414
J 0
(-6052 3725);
DISPLAY 0.872340 (-6052 3725);
PAINT GREEN (-6052 3725);
DISPLAY INVISIBLE (-6052 3725);
FORCEADD TAP..1
(-6050 3775);
FORCEPROP 3 LASTPIN (-6100 3775) SIG_NAME M_A_CPU0_SB_DQ<31>
J 0
(-6090 3785);
DISPLAY 0.659574 (-6090 3785);
PAINT MONO (-6090 3785);
DISPLAY INVISIBLE (-6090 3785);
FORCEPROP 1 LASTPIN (-6100 3775) BN 31
J 0
(-6112 3783);
DISPLAY 0.489362 (-6112 3783);
PAINT GREEN (-6112 3783);
FORCEPROP 2 LAST CDS_LIB mstr_standard
J 0
(-6050 3775);
DISPLAY 0.723404 (-6050 3775);
PAINT MONO (-6050 3775);
DISPLAY INVISIBLE (-6050 3775);
FORCEPROP 1 LAST BODY_TYPE PLUMBING
J 0
(-6050 3825);
DISPLAY 0.872340 (-6050 3825);
PAINT GREEN (-6050 3825);
DISPLAY INVISIBLE (-6050 3825);
FORCEPROP 1 LAST HDL_TAP TRUE
J 0
(-5725 3650);
DISPLAY 0.872340 (-5725 3650);
DISPLAY INVISIBLE (-5725 3650);
FORCEPROP 1 LAST PATH I415
J 0
(-6052 3775);
DISPLAY 0.872340 (-6052 3775);
PAINT GREEN (-6052 3775);
DISPLAY INVISIBLE (-6052 3775);
FORCEADD TAP..1
(-6050 3975);
FORCEPROP 3 LASTPIN (-6100 3975) SIG_NAME M_A_CPU0_SA_DQ<2>
J 0
(-6090 3985);
DISPLAY 0.659574 (-6090 3985);
PAINT MONO (-6090 3985);
DISPLAY INVISIBLE (-6090 3985);
FORCEPROP 1 LASTPIN (-6100 3975) BN 2
J 0
(-6112 3983);
DISPLAY 0.489362 (-6112 3983);
PAINT GREEN (-6112 3983);
FORCEPROP 2 LAST CDS_LIB mstr_standard
J 0
(-6050 3975);
DISPLAY 0.723404 (-6050 3975);
PAINT MONO (-6050 3975);
DISPLAY INVISIBLE (-6050 3975);
FORCEPROP 1 LAST BODY_TYPE PLUMBING
J 0
(-6050 4025);
DISPLAY 0.872340 (-6050 4025);
PAINT GREEN (-6050 4025);
DISPLAY INVISIBLE (-6050 4025);
FORCEPROP 1 LAST HDL_TAP TRUE
J 0
(-5725 3850);
DISPLAY 0.872340 (-5725 3850);
DISPLAY INVISIBLE (-5725 3850);
FORCEPROP 1 LAST PATH I416
J 0
(-6052 3975);
DISPLAY 0.872340 (-6052 3975);
PAINT GREEN (-6052 3975);
DISPLAY INVISIBLE (-6052 3975);
FORCEADD TAP..1
(-6050 3925);
FORCEPROP 3 LASTPIN (-6100 3925) SIG_NAME M_A_CPU0_SA_DQ<1>
J 0
(-6090 3935);
DISPLAY 0.659574 (-6090 3935);
PAINT MONO (-6090 3935);
DISPLAY INVISIBLE (-6090 3935);
FORCEPROP 1 LASTPIN (-6100 3925) BN 1
J 0
(-6112 3933);
DISPLAY 0.489362 (-6112 3933);
PAINT GREEN (-6112 3933);
FORCEPROP 2 LAST CDS_LIB mstr_standard
J 0
(-6050 3925);
DISPLAY 0.723404 (-6050 3925);
PAINT MONO (-6050 3925);
DISPLAY INVISIBLE (-6050 3925);
FORCEPROP 1 LAST BODY_TYPE PLUMBING
J 0
(-6050 3975);
DISPLAY 0.872340 (-6050 3975);
PAINT GREEN (-6050 3975);
DISPLAY INVISIBLE (-6050 3975);
FORCEPROP 1 LAST HDL_TAP TRUE
J 0
(-5725 3800);
DISPLAY 0.872340 (-5725 3800);
DISPLAY INVISIBLE (-5725 3800);
FORCEPROP 1 LAST PATH I417
J 0
(-6052 3925);
DISPLAY 0.872340 (-6052 3925);
PAINT GREEN (-6052 3925);
DISPLAY INVISIBLE (-6052 3925);
FORCEADD TAP..1
(-6050 4025);
FORCEPROP 3 LASTPIN (-6100 4025) SIG_NAME M_A_CPU0_SA_DQ<3>
J 0
(-6090 4035);
DISPLAY 0.659574 (-6090 4035);
PAINT MONO (-6090 4035);
DISPLAY INVISIBLE (-6090 4035);
FORCEPROP 1 LASTPIN (-6100 4025) BN 3
J 0
(-6112 4033);
DISPLAY 0.489362 (-6112 4033);
PAINT GREEN (-6112 4033);
FORCEPROP 2 LAST CDS_LIB mstr_standard
J 0
(-6050 4025);
DISPLAY 0.723404 (-6050 4025);
PAINT MONO (-6050 4025);
DISPLAY INVISIBLE (-6050 4025);
FORCEPROP 1 LAST BODY_TYPE PLUMBING
J 0
(-6050 4075);
DISPLAY 0.872340 (-6050 4075);
PAINT GREEN (-6050 4075);
DISPLAY INVISIBLE (-6050 4075);
FORCEPROP 1 LAST HDL_TAP TRUE
J 0
(-5725 3900);
DISPLAY 0.872340 (-5725 3900);
DISPLAY INVISIBLE (-5725 3900);
FORCEPROP 1 LAST PATH I418
J 0
(-6052 4025);
DISPLAY 0.872340 (-6052 4025);
PAINT GREEN (-6052 4025);
DISPLAY INVISIBLE (-6052 4025);
FORCEADD TAP..1
(-6050 4125);
FORCEPROP 3 LASTPIN (-6100 4125) SIG_NAME M_A_CPU0_SA_DQ<5>
J 0
(-6090 4135);
DISPLAY 0.659574 (-6090 4135);
PAINT MONO (-6090 4135);
DISPLAY INVISIBLE (-6090 4135);
FORCEPROP 1 LASTPIN (-6100 4125) BN 5
J 0
(-6112 4133);
DISPLAY 0.489362 (-6112 4133);
PAINT GREEN (-6112 4133);
FORCEPROP 2 LAST CDS_LIB mstr_standard
J 0
(-6050 4125);
DISPLAY 0.723404 (-6050 4125);
PAINT MONO (-6050 4125);
DISPLAY INVISIBLE (-6050 4125);
FORCEPROP 1 LAST BODY_TYPE PLUMBING
J 0
(-6050 4175);
DISPLAY 0.872340 (-6050 4175);
PAINT GREEN (-6050 4175);
DISPLAY INVISIBLE (-6050 4175);
FORCEPROP 1 LAST HDL_TAP TRUE
J 0
(-5725 4000);
DISPLAY 0.872340 (-5725 4000);
DISPLAY INVISIBLE (-5725 4000);
FORCEPROP 1 LAST PATH I419
J 0
(-6052 4125);
DISPLAY 0.872340 (-6052 4125);
PAINT GREEN (-6052 4125);
DISPLAY INVISIBLE (-6052 4125);
FORCEADD TAP..1
(-6050 4075);
FORCEPROP 3 LASTPIN (-6100 4075) SIG_NAME M_A_CPU0_SA_DQ<4>
J 0
(-6090 4085);
DISPLAY 0.659574 (-6090 4085);
PAINT MONO (-6090 4085);
DISPLAY INVISIBLE (-6090 4085);
FORCEPROP 1 LASTPIN (-6100 4075) BN 4
J 0
(-6112 4083);
DISPLAY 0.489362 (-6112 4083);
PAINT GREEN (-6112 4083);
FORCEPROP 2 LAST CDS_LIB mstr_standard
J 0
(-6050 4075);
DISPLAY 0.723404 (-6050 4075);
PAINT MONO (-6050 4075);
DISPLAY INVISIBLE (-6050 4075);
FORCEPROP 1 LAST BODY_TYPE PLUMBING
J 0
(-6050 4125);
DISPLAY 0.872340 (-6050 4125);
PAINT GREEN (-6050 4125);
DISPLAY INVISIBLE (-6050 4125);
FORCEPROP 1 LAST HDL_TAP TRUE
J 0
(-5725 3950);
DISPLAY 0.872340 (-5725 3950);
DISPLAY INVISIBLE (-5725 3950);
FORCEPROP 1 LAST PATH I420
J 0
(-6052 4075);
DISPLAY 0.872340 (-6052 4075);
PAINT GREEN (-6052 4075);
DISPLAY INVISIBLE (-6052 4075);
FORCEADD TAP..1
(-6050 4225);
FORCEPROP 3 LASTPIN (-6100 4225) SIG_NAME M_A_CPU0_SA_DQ<7>
J 0
(-6090 4235);
DISPLAY 0.659574 (-6090 4235);
PAINT MONO (-6090 4235);
DISPLAY INVISIBLE (-6090 4235);
FORCEPROP 1 LASTPIN (-6100 4225) BN 7
J 0
(-6112 4233);
DISPLAY 0.489362 (-6112 4233);
PAINT GREEN (-6112 4233);
FORCEPROP 2 LAST CDS_LIB mstr_standard
J 0
(-6050 4225);
DISPLAY 0.723404 (-6050 4225);
PAINT MONO (-6050 4225);
DISPLAY INVISIBLE (-6050 4225);
FORCEPROP 1 LAST BODY_TYPE PLUMBING
J 0
(-6050 4275);
DISPLAY 0.872340 (-6050 4275);
PAINT GREEN (-6050 4275);
DISPLAY INVISIBLE (-6050 4275);
FORCEPROP 1 LAST HDL_TAP TRUE
J 0
(-5725 4100);
DISPLAY 0.872340 (-5725 4100);
DISPLAY INVISIBLE (-5725 4100);
FORCEPROP 1 LAST PATH I421
J 0
(-6052 4225);
DISPLAY 0.872340 (-6052 4225);
PAINT GREEN (-6052 4225);
DISPLAY INVISIBLE (-6052 4225);
FORCEADD TAP..1
(-6050 4175);
FORCEPROP 3 LASTPIN (-6100 4175) SIG_NAME M_A_CPU0_SA_DQ<6>
J 0
(-6090 4185);
DISPLAY 0.659574 (-6090 4185);
PAINT MONO (-6090 4185);
DISPLAY INVISIBLE (-6090 4185);
FORCEPROP 1 LASTPIN (-6100 4175) BN 6
J 0
(-6112 4183);
DISPLAY 0.489362 (-6112 4183);
PAINT GREEN (-6112 4183);
FORCEPROP 2 LAST CDS_LIB mstr_standard
J 0
(-6050 4175);
DISPLAY 0.723404 (-6050 4175);
PAINT MONO (-6050 4175);
DISPLAY INVISIBLE (-6050 4175);
FORCEPROP 1 LAST BODY_TYPE PLUMBING
J 0
(-6050 4225);
DISPLAY 0.872340 (-6050 4225);
PAINT GREEN (-6050 4225);
DISPLAY INVISIBLE (-6050 4225);
FORCEPROP 1 LAST HDL_TAP TRUE
J 0
(-5725 4050);
DISPLAY 0.872340 (-5725 4050);
DISPLAY INVISIBLE (-5725 4050);
FORCEPROP 1 LAST PATH I422
J 0
(-6052 4175);
DISPLAY 0.872340 (-6052 4175);
PAINT GREEN (-6052 4175);
DISPLAY INVISIBLE (-6052 4175);
FORCEADD TAP..1
(-6050 4275);
FORCEPROP 3 LASTPIN (-6100 4275) SIG_NAME M_A_CPU0_SA_DQ<8>
J 0
(-6090 4285);
DISPLAY 0.659574 (-6090 4285);
PAINT MONO (-6090 4285);
DISPLAY INVISIBLE (-6090 4285);
FORCEPROP 1 LASTPIN (-6100 4275) BN 8
J 0
(-6112 4283);
DISPLAY 0.489362 (-6112 4283);
PAINT GREEN (-6112 4283);
FORCEPROP 2 LAST CDS_LIB mstr_standard
J 0
(-6050 4275);
DISPLAY 0.723404 (-6050 4275);
PAINT MONO (-6050 4275);
DISPLAY INVISIBLE (-6050 4275);
FORCEPROP 1 LAST BODY_TYPE PLUMBING
J 0
(-6050 4325);
DISPLAY 0.872340 (-6050 4325);
PAINT GREEN (-6050 4325);
DISPLAY INVISIBLE (-6050 4325);
FORCEPROP 1 LAST HDL_TAP TRUE
J 0
(-5725 4150);
DISPLAY 0.872340 (-5725 4150);
DISPLAY INVISIBLE (-5725 4150);
FORCEPROP 1 LAST PATH I423
J 0
(-6052 4275);
DISPLAY 0.872340 (-6052 4275);
PAINT GREEN (-6052 4275);
DISPLAY INVISIBLE (-6052 4275);
FORCEADD TAP..1
(-6050 4375);
FORCEPROP 3 LASTPIN (-6100 4375) SIG_NAME M_A_CPU0_SA_DQ<10>
J 0
(-6090 4385);
DISPLAY 0.659574 (-6090 4385);
PAINT MONO (-6090 4385);
DISPLAY INVISIBLE (-6090 4385);
FORCEPROP 1 LASTPIN (-6100 4375) BN 10
J 0
(-6112 4383);
DISPLAY 0.489362 (-6112 4383);
PAINT GREEN (-6112 4383);
FORCEPROP 2 LAST CDS_LIB mstr_standard
J 0
(-6050 4375);
DISPLAY 0.723404 (-6050 4375);
PAINT MONO (-6050 4375);
DISPLAY INVISIBLE (-6050 4375);
FORCEPROP 1 LAST BODY_TYPE PLUMBING
J 0
(-6050 4425);
DISPLAY 0.872340 (-6050 4425);
PAINT GREEN (-6050 4425);
DISPLAY INVISIBLE (-6050 4425);
FORCEPROP 1 LAST HDL_TAP TRUE
J 0
(-5725 4250);
DISPLAY 0.872340 (-5725 4250);
DISPLAY INVISIBLE (-5725 4250);
FORCEPROP 1 LAST PATH I424
J 0
(-6052 4375);
DISPLAY 0.872340 (-6052 4375);
PAINT GREEN (-6052 4375);
DISPLAY INVISIBLE (-6052 4375);
FORCEADD TAP..1
(-6050 4325);
FORCEPROP 3 LASTPIN (-6100 4325) SIG_NAME M_A_CPU0_SA_DQ<9>
J 0
(-6090 4335);
DISPLAY 0.659574 (-6090 4335);
PAINT MONO (-6090 4335);
DISPLAY INVISIBLE (-6090 4335);
FORCEPROP 1 LASTPIN (-6100 4325) BN 9
J 0
(-6112 4333);
DISPLAY 0.489362 (-6112 4333);
PAINT GREEN (-6112 4333);
FORCEPROP 2 LAST CDS_LIB mstr_standard
J 0
(-6050 4325);
DISPLAY 0.723404 (-6050 4325);
PAINT MONO (-6050 4325);
DISPLAY INVISIBLE (-6050 4325);
FORCEPROP 1 LAST BODY_TYPE PLUMBING
J 0
(-6050 4375);
DISPLAY 0.872340 (-6050 4375);
PAINT GREEN (-6050 4375);
DISPLAY INVISIBLE (-6050 4375);
FORCEPROP 1 LAST HDL_TAP TRUE
J 0
(-5725 4200);
DISPLAY 0.872340 (-5725 4200);
DISPLAY INVISIBLE (-5725 4200);
FORCEPROP 1 LAST PATH I425
J 0
(-6052 4325);
DISPLAY 0.872340 (-6052 4325);
PAINT GREEN (-6052 4325);
DISPLAY INVISIBLE (-6052 4325);
FORCEADD TAP..1
(-6050 4425);
FORCEPROP 3 LASTPIN (-6100 4425) SIG_NAME M_A_CPU0_SA_DQ<11>
J 0
(-6090 4435);
DISPLAY 0.659574 (-6090 4435);
PAINT MONO (-6090 4435);
DISPLAY INVISIBLE (-6090 4435);
FORCEPROP 1 LASTPIN (-6100 4425) BN 11
J 0
(-6112 4433);
DISPLAY 0.489362 (-6112 4433);
PAINT GREEN (-6112 4433);
FORCEPROP 2 LAST CDS_LIB mstr_standard
J 0
(-6050 4425);
DISPLAY 0.723404 (-6050 4425);
PAINT MONO (-6050 4425);
DISPLAY INVISIBLE (-6050 4425);
FORCEPROP 1 LAST BODY_TYPE PLUMBING
J 0
(-6050 4475);
DISPLAY 0.872340 (-6050 4475);
PAINT GREEN (-6050 4475);
DISPLAY INVISIBLE (-6050 4475);
FORCEPROP 1 LAST HDL_TAP TRUE
J 0
(-5725 4300);
DISPLAY 0.872340 (-5725 4300);
DISPLAY INVISIBLE (-5725 4300);
FORCEPROP 1 LAST PATH I426
J 0
(-6052 4425);
DISPLAY 0.872340 (-6052 4425);
PAINT GREEN (-6052 4425);
DISPLAY INVISIBLE (-6052 4425);
FORCEADD TAP..1
(-6050 4475);
FORCEPROP 3 LASTPIN (-6100 4475) SIG_NAME M_A_CPU0_SA_DQ<12>
J 0
(-6090 4485);
DISPLAY 0.659574 (-6090 4485);
PAINT MONO (-6090 4485);
DISPLAY INVISIBLE (-6090 4485);
FORCEPROP 1 LASTPIN (-6100 4475) BN 12
J 0
(-6112 4483);
DISPLAY 0.489362 (-6112 4483);
PAINT GREEN (-6112 4483);
FORCEPROP 2 LAST CDS_LIB mstr_standard
J 0
(-6050 4475);
DISPLAY 0.723404 (-6050 4475);
PAINT MONO (-6050 4475);
DISPLAY INVISIBLE (-6050 4475);
FORCEPROP 1 LAST BODY_TYPE PLUMBING
J 0
(-6050 4525);
DISPLAY 0.872340 (-6050 4525);
PAINT GREEN (-6050 4525);
DISPLAY INVISIBLE (-6050 4525);
FORCEPROP 1 LAST HDL_TAP TRUE
J 0
(-5725 4350);
DISPLAY 0.872340 (-5725 4350);
DISPLAY INVISIBLE (-5725 4350);
FORCEPROP 1 LAST PATH I427
J 0
(-6052 4475);
DISPLAY 0.872340 (-6052 4475);
PAINT GREEN (-6052 4475);
DISPLAY INVISIBLE (-6052 4475);
FORCEADD TAP..1
(-6050 4525);
FORCEPROP 3 LASTPIN (-6100 4525) SIG_NAME M_A_CPU0_SA_DQ<13>
J 0
(-6090 4535);
DISPLAY 0.659574 (-6090 4535);
PAINT MONO (-6090 4535);
DISPLAY INVISIBLE (-6090 4535);
FORCEPROP 1 LASTPIN (-6100 4525) BN 13
J 0
(-6112 4533);
DISPLAY 0.489362 (-6112 4533);
PAINT GREEN (-6112 4533);
FORCEPROP 2 LAST CDS_LIB mstr_standard
J 0
(-6050 4525);
DISPLAY 0.723404 (-6050 4525);
PAINT MONO (-6050 4525);
DISPLAY INVISIBLE (-6050 4525);
FORCEPROP 1 LAST BODY_TYPE PLUMBING
J 0
(-6050 4575);
DISPLAY 0.872340 (-6050 4575);
PAINT GREEN (-6050 4575);
DISPLAY INVISIBLE (-6050 4575);
FORCEPROP 1 LAST HDL_TAP TRUE
J 0
(-5725 4400);
DISPLAY 0.872340 (-5725 4400);
DISPLAY INVISIBLE (-5725 4400);
FORCEPROP 1 LAST PATH I428
J 0
(-6052 4525);
DISPLAY 0.872340 (-6052 4525);
PAINT GREEN (-6052 4525);
DISPLAY INVISIBLE (-6052 4525);
FORCEADD TAP..1
(-6050 4575);
FORCEPROP 3 LASTPIN (-6100 4575) SIG_NAME M_A_CPU0_SA_DQ<14>
J 0
(-6090 4585);
DISPLAY 0.659574 (-6090 4585);
PAINT MONO (-6090 4585);
DISPLAY INVISIBLE (-6090 4585);
FORCEPROP 1 LASTPIN (-6100 4575) BN 14
J 0
(-6112 4583);
DISPLAY 0.489362 (-6112 4583);
PAINT GREEN (-6112 4583);
FORCEPROP 2 LAST CDS_LIB mstr_standard
J 0
(-6050 4575);
DISPLAY 0.723404 (-6050 4575);
PAINT MONO (-6050 4575);
DISPLAY INVISIBLE (-6050 4575);
FORCEPROP 1 LAST BODY_TYPE PLUMBING
J 0
(-6050 4625);
DISPLAY 0.872340 (-6050 4625);
PAINT GREEN (-6050 4625);
DISPLAY INVISIBLE (-6050 4625);
FORCEPROP 1 LAST HDL_TAP TRUE
J 0
(-5725 4450);
DISPLAY 0.872340 (-5725 4450);
DISPLAY INVISIBLE (-5725 4450);
FORCEPROP 1 LAST PATH I429
J 0
(-6052 4575);
DISPLAY 0.872340 (-6052 4575);
PAINT GREEN (-6052 4575);
DISPLAY INVISIBLE (-6052 4575);
FORCEADD TAP..1
(-6050 4625);
FORCEPROP 3 LASTPIN (-6100 4625) SIG_NAME M_A_CPU0_SA_DQ<15>
J 0
(-6090 4635);
DISPLAY 0.659574 (-6090 4635);
PAINT MONO (-6090 4635);
DISPLAY INVISIBLE (-6090 4635);
FORCEPROP 1 LASTPIN (-6100 4625) BN 15
J 0
(-6112 4633);
DISPLAY 0.489362 (-6112 4633);
PAINT GREEN (-6112 4633);
FORCEPROP 2 LAST CDS_LIB mstr_standard
J 0
(-6050 4625);
DISPLAY 0.723404 (-6050 4625);
PAINT MONO (-6050 4625);
DISPLAY INVISIBLE (-6050 4625);
FORCEPROP 1 LAST BODY_TYPE PLUMBING
J 0
(-6050 4675);
DISPLAY 0.872340 (-6050 4675);
PAINT GREEN (-6050 4675);
DISPLAY INVISIBLE (-6050 4675);
FORCEPROP 1 LAST HDL_TAP TRUE
J 0
(-5725 4500);
DISPLAY 0.872340 (-5725 4500);
DISPLAY INVISIBLE (-5725 4500);
FORCEPROP 1 LAST PATH I430
J 0
(-6052 4625);
DISPLAY 0.872340 (-6052 4625);
PAINT GREEN (-6052 4625);
DISPLAY INVISIBLE (-6052 4625);
FORCEADD TAP..1
(-6050 4825);
FORCEPROP 3 LASTPIN (-6100 4825) SIG_NAME M_A_CPU0_SA_DQ<19>
J 0
(-6090 4835);
DISPLAY 0.659574 (-6090 4835);
PAINT MONO (-6090 4835);
DISPLAY INVISIBLE (-6090 4835);
FORCEPROP 1 LASTPIN (-6100 4825) BN 19
J 0
(-6112 4833);
DISPLAY 0.489362 (-6112 4833);
PAINT GREEN (-6112 4833);
FORCEPROP 2 LAST CDS_LIB mstr_standard
J 0
(-6050 4825);
DISPLAY 0.723404 (-6050 4825);
PAINT MONO (-6050 4825);
DISPLAY INVISIBLE (-6050 4825);
FORCEPROP 1 LAST BODY_TYPE PLUMBING
J 0
(-6050 4875);
DISPLAY 0.872340 (-6050 4875);
PAINT GREEN (-6050 4875);
DISPLAY INVISIBLE (-6050 4875);
FORCEPROP 1 LAST HDL_TAP TRUE
J 0
(-5725 4700);
DISPLAY 0.872340 (-5725 4700);
DISPLAY INVISIBLE (-5725 4700);
FORCEPROP 1 LAST PATH I431
J 0
(-6052 4825);
DISPLAY 0.872340 (-6052 4825);
PAINT GREEN (-6052 4825);
DISPLAY INVISIBLE (-6052 4825);
FORCEADD TAP..1
(-6050 4875);
FORCEPROP 3 LASTPIN (-6100 4875) SIG_NAME M_A_CPU0_SA_DQ<20>
J 0
(-6090 4885);
DISPLAY 0.659574 (-6090 4885);
PAINT MONO (-6090 4885);
DISPLAY INVISIBLE (-6090 4885);
FORCEPROP 1 LASTPIN (-6100 4875) BN 20
J 0
(-6112 4883);
DISPLAY 0.489362 (-6112 4883);
PAINT GREEN (-6112 4883);
FORCEPROP 2 LAST CDS_LIB mstr_standard
J 0
(-6050 4875);
DISPLAY 0.723404 (-6050 4875);
PAINT MONO (-6050 4875);
DISPLAY INVISIBLE (-6050 4875);
FORCEPROP 1 LAST BODY_TYPE PLUMBING
J 0
(-6050 4925);
DISPLAY 0.872340 (-6050 4925);
PAINT GREEN (-6050 4925);
DISPLAY INVISIBLE (-6050 4925);
FORCEPROP 1 LAST HDL_TAP TRUE
J 0
(-5725 4750);
DISPLAY 0.872340 (-5725 4750);
DISPLAY INVISIBLE (-5725 4750);
FORCEPROP 1 LAST PATH I432
J 0
(-6052 4875);
DISPLAY 0.872340 (-6052 4875);
PAINT GREEN (-6052 4875);
DISPLAY INVISIBLE (-6052 4875);
FORCEADD TAP..1
(-6050 4675);
FORCEPROP 3 LASTPIN (-6100 4675) SIG_NAME M_A_CPU0_SA_DQ<16>
J 0
(-6090 4685);
DISPLAY 0.659574 (-6090 4685);
PAINT MONO (-6090 4685);
DISPLAY INVISIBLE (-6090 4685);
FORCEPROP 1 LASTPIN (-6100 4675) BN 16
J 0
(-6112 4683);
DISPLAY 0.489362 (-6112 4683);
PAINT GREEN (-6112 4683);
FORCEPROP 2 LAST CDS_LIB mstr_standard
J 0
(-6050 4675);
DISPLAY 0.723404 (-6050 4675);
PAINT MONO (-6050 4675);
DISPLAY INVISIBLE (-6050 4675);
FORCEPROP 1 LAST BODY_TYPE PLUMBING
J 0
(-6050 4725);
DISPLAY 0.872340 (-6050 4725);
PAINT GREEN (-6050 4725);
DISPLAY INVISIBLE (-6050 4725);
FORCEPROP 1 LAST HDL_TAP TRUE
J 0
(-5725 4550);
DISPLAY 0.872340 (-5725 4550);
DISPLAY INVISIBLE (-5725 4550);
FORCEPROP 1 LAST PATH I433
J 0
(-6052 4675);
DISPLAY 0.872340 (-6052 4675);
PAINT GREEN (-6052 4675);
DISPLAY INVISIBLE (-6052 4675);
FORCEADD TAP..1
(-6050 4725);
FORCEPROP 3 LASTPIN (-6100 4725) SIG_NAME M_A_CPU0_SA_DQ<17>
J 0
(-6090 4735);
DISPLAY 0.659574 (-6090 4735);
PAINT MONO (-6090 4735);
DISPLAY INVISIBLE (-6090 4735);
FORCEPROP 1 LASTPIN (-6100 4725) BN 17
J 0
(-6112 4733);
DISPLAY 0.489362 (-6112 4733);
PAINT GREEN (-6112 4733);
FORCEPROP 2 LAST CDS_LIB mstr_standard
J 0
(-6050 4725);
DISPLAY 0.723404 (-6050 4725);
PAINT MONO (-6050 4725);
DISPLAY INVISIBLE (-6050 4725);
FORCEPROP 1 LAST BODY_TYPE PLUMBING
J 0
(-6050 4775);
DISPLAY 0.872340 (-6050 4775);
PAINT GREEN (-6050 4775);
DISPLAY INVISIBLE (-6050 4775);
FORCEPROP 1 LAST HDL_TAP TRUE
J 0
(-5725 4600);
DISPLAY 0.872340 (-5725 4600);
DISPLAY INVISIBLE (-5725 4600);
FORCEPROP 1 LAST PATH I434
J 0
(-6052 4725);
DISPLAY 0.872340 (-6052 4725);
PAINT GREEN (-6052 4725);
DISPLAY INVISIBLE (-6052 4725);
FORCEADD TAP..1
(-6050 4775);
FORCEPROP 3 LASTPIN (-6100 4775) SIG_NAME M_A_CPU0_SA_DQ<18>
J 0
(-6090 4785);
DISPLAY 0.659574 (-6090 4785);
PAINT MONO (-6090 4785);
DISPLAY INVISIBLE (-6090 4785);
FORCEPROP 1 LASTPIN (-6100 4775) BN 18
J 0
(-6112 4783);
DISPLAY 0.489362 (-6112 4783);
PAINT GREEN (-6112 4783);
FORCEPROP 2 LAST CDS_LIB mstr_standard
J 0
(-6050 4775);
DISPLAY 0.723404 (-6050 4775);
PAINT MONO (-6050 4775);
DISPLAY INVISIBLE (-6050 4775);
FORCEPROP 1 LAST BODY_TYPE PLUMBING
J 0
(-6050 4825);
DISPLAY 0.872340 (-6050 4825);
PAINT GREEN (-6050 4825);
DISPLAY INVISIBLE (-6050 4825);
FORCEPROP 1 LAST HDL_TAP TRUE
J 0
(-5725 4650);
DISPLAY 0.872340 (-5725 4650);
DISPLAY INVISIBLE (-5725 4650);
FORCEPROP 1 LAST PATH I435
J 0
(-6052 4775);
DISPLAY 0.872340 (-6052 4775);
PAINT GREEN (-6052 4775);
DISPLAY INVISIBLE (-6052 4775);
FORCEADD OFFPAGE..3
(-5500 3825);
FORCEPROP 2 LAST $XR0 10 
J 0
(-5286 3825);
DISPLAY 0.638298 (-5286 3825);
PAINT MONO (-5286 3825);
FORCEPROP 2 LAST PATH I436
J 0
(-5175 3875);
DISPLAY 0.808511 (-5175 3875);
DISPLAY INVISIBLE (-5175 3875);
FORCEPROP 1 LAST COMMENT_BODY TRUE
J 0
(-5550 3725);
DISPLAY 0.872340 (-5550 3725);
PAINT GREEN (-5550 3725);
DISPLAY INVISIBLE (-5550 3725);
FORCEPROP 1 LAST OFFPAGE TRUE
J 0
(-5175 3700);
DISPLAY 0.872340 (-5175 3700);
PAINT GREEN (-5175 3700);
DISPLAY INVISIBLE (-5175 3700);
FORCEPROP 2 LAST CDS_LIB mstr_standard
J 0
(-5500 3825);
DISPLAY 0.723404 (-5500 3825);
PAINT MONO (-5500 3825);
DISPLAY INVISIBLE (-5500 3825);
FORCEADD TAP..1
(-6050 5025);
FORCEPROP 3 LASTPIN (-6100 5025) SIG_NAME M_A_CPU0_SA_DQ<23>
J 0
(-6090 5035);
DISPLAY 0.659574 (-6090 5035);
PAINT MONO (-6090 5035);
DISPLAY INVISIBLE (-6090 5035);
FORCEPROP 1 LASTPIN (-6100 5025) BN 23
J 0
(-6112 5033);
DISPLAY 0.489362 (-6112 5033);
PAINT GREEN (-6112 5033);
FORCEPROP 2 LAST CDS_LIB mstr_standard
J 0
(-6050 5025);
DISPLAY 0.723404 (-6050 5025);
PAINT MONO (-6050 5025);
DISPLAY INVISIBLE (-6050 5025);
FORCEPROP 1 LAST BODY_TYPE PLUMBING
J 0
(-6050 5075);
DISPLAY 0.872340 (-6050 5075);
PAINT GREEN (-6050 5075);
DISPLAY INVISIBLE (-6050 5075);
FORCEPROP 1 LAST HDL_TAP TRUE
J 0
(-5725 4900);
DISPLAY 0.872340 (-5725 4900);
DISPLAY INVISIBLE (-5725 4900);
FORCEPROP 1 LAST PATH I437
J 0
(-6052 5025);
DISPLAY 0.872340 (-6052 5025);
PAINT GREEN (-6052 5025);
DISPLAY INVISIBLE (-6052 5025);
FORCEADD TAP..1
(-6050 4925);
FORCEPROP 3 LASTPIN (-6100 4925) SIG_NAME M_A_CPU0_SA_DQ<21>
J 0
(-6090 4935);
DISPLAY 0.659574 (-6090 4935);
PAINT MONO (-6090 4935);
DISPLAY INVISIBLE (-6090 4935);
FORCEPROP 1 LASTPIN (-6100 4925) BN 21
J 0
(-6112 4933);
DISPLAY 0.489362 (-6112 4933);
PAINT GREEN (-6112 4933);
FORCEPROP 2 LAST CDS_LIB mstr_standard
J 0
(-6050 4925);
DISPLAY 0.723404 (-6050 4925);
PAINT MONO (-6050 4925);
DISPLAY INVISIBLE (-6050 4925);
FORCEPROP 1 LAST BODY_TYPE PLUMBING
J 0
(-6050 4975);
DISPLAY 0.872340 (-6050 4975);
PAINT GREEN (-6050 4975);
DISPLAY INVISIBLE (-6050 4975);
FORCEPROP 1 LAST HDL_TAP TRUE
J 0
(-5725 4800);
DISPLAY 0.872340 (-5725 4800);
DISPLAY INVISIBLE (-5725 4800);
FORCEPROP 1 LAST PATH I438
J 0
(-6052 4925);
DISPLAY 0.872340 (-6052 4925);
PAINT GREEN (-6052 4925);
DISPLAY INVISIBLE (-6052 4925);
FORCEADD TAP..1
(-6050 4975);
FORCEPROP 3 LASTPIN (-6100 4975) SIG_NAME M_A_CPU0_SA_DQ<22>
J 0
(-6090 4985);
DISPLAY 0.659574 (-6090 4985);
PAINT MONO (-6090 4985);
DISPLAY INVISIBLE (-6090 4985);
FORCEPROP 1 LASTPIN (-6100 4975) BN 22
J 0
(-6112 4983);
DISPLAY 0.489362 (-6112 4983);
PAINT GREEN (-6112 4983);
FORCEPROP 2 LAST CDS_LIB mstr_standard
J 0
(-6050 4975);
DISPLAY 0.723404 (-6050 4975);
PAINT MONO (-6050 4975);
DISPLAY INVISIBLE (-6050 4975);
FORCEPROP 1 LAST BODY_TYPE PLUMBING
J 0
(-6050 5025);
DISPLAY 0.872340 (-6050 5025);
PAINT GREEN (-6050 5025);
DISPLAY INVISIBLE (-6050 5025);
FORCEPROP 1 LAST HDL_TAP TRUE
J 0
(-5725 4850);
DISPLAY 0.872340 (-5725 4850);
DISPLAY INVISIBLE (-5725 4850);
FORCEPROP 1 LAST PATH I439
J 0
(-6052 4975);
DISPLAY 0.872340 (-6052 4975);
PAINT GREEN (-6052 4975);
DISPLAY INVISIBLE (-6052 4975);
FORCEADD TAP..1
(-6050 5175);
FORCEPROP 3 LASTPIN (-6100 5175) SIG_NAME M_A_CPU0_SA_DQ<26>
J 0
(-6090 5185);
DISPLAY 0.659574 (-6090 5185);
PAINT MONO (-6090 5185);
DISPLAY INVISIBLE (-6090 5185);
FORCEPROP 1 LASTPIN (-6100 5175) BN 26
J 0
(-6112 5183);
DISPLAY 0.489362 (-6112 5183);
PAINT GREEN (-6112 5183);
FORCEPROP 2 LAST CDS_LIB mstr_standard
J 0
(-6050 5175);
DISPLAY 0.723404 (-6050 5175);
PAINT MONO (-6050 5175);
DISPLAY INVISIBLE (-6050 5175);
FORCEPROP 1 LAST BODY_TYPE PLUMBING
J 0
(-6050 5225);
DISPLAY 0.872340 (-6050 5225);
PAINT GREEN (-6050 5225);
DISPLAY INVISIBLE (-6050 5225);
FORCEPROP 1 LAST HDL_TAP TRUE
J 0
(-5725 5050);
DISPLAY 0.872340 (-5725 5050);
DISPLAY INVISIBLE (-5725 5050);
FORCEPROP 1 LAST PATH I440
J 0
(-6052 5175);
DISPLAY 0.872340 (-6052 5175);
PAINT GREEN (-6052 5175);
DISPLAY INVISIBLE (-6052 5175);
FORCEADD TAP..1
(-6050 5125);
FORCEPROP 3 LASTPIN (-6100 5125) SIG_NAME M_A_CPU0_SA_DQ<25>
J 0
(-6090 5135);
DISPLAY 0.659574 (-6090 5135);
PAINT MONO (-6090 5135);
DISPLAY INVISIBLE (-6090 5135);
FORCEPROP 1 LASTPIN (-6100 5125) BN 25
J 0
(-6112 5133);
DISPLAY 0.489362 (-6112 5133);
PAINT GREEN (-6112 5133);
FORCEPROP 2 LAST CDS_LIB mstr_standard
J 0
(-6050 5125);
DISPLAY 0.723404 (-6050 5125);
PAINT MONO (-6050 5125);
DISPLAY INVISIBLE (-6050 5125);
FORCEPROP 1 LAST BODY_TYPE PLUMBING
J 0
(-6050 5175);
DISPLAY 0.872340 (-6050 5175);
PAINT GREEN (-6050 5175);
DISPLAY INVISIBLE (-6050 5175);
FORCEPROP 1 LAST HDL_TAP TRUE
J 0
(-5725 5000);
DISPLAY 0.872340 (-5725 5000);
DISPLAY INVISIBLE (-5725 5000);
FORCEPROP 1 LAST PATH I441
J 0
(-6052 5125);
DISPLAY 0.872340 (-6052 5125);
PAINT GREEN (-6052 5125);
DISPLAY INVISIBLE (-6052 5125);
FORCEADD TAP..1
(-6050 5075);
FORCEPROP 3 LASTPIN (-6100 5075) SIG_NAME M_A_CPU0_SA_DQ<24>
J 0
(-6090 5085);
DISPLAY 0.659574 (-6090 5085);
PAINT MONO (-6090 5085);
DISPLAY INVISIBLE (-6090 5085);
FORCEPROP 1 LASTPIN (-6100 5075) BN 24
J 0
(-6112 5083);
DISPLAY 0.489362 (-6112 5083);
PAINT GREEN (-6112 5083);
FORCEPROP 2 LAST CDS_LIB mstr_standard
J 0
(-6050 5075);
DISPLAY 0.723404 (-6050 5075);
PAINT MONO (-6050 5075);
DISPLAY INVISIBLE (-6050 5075);
FORCEPROP 1 LAST BODY_TYPE PLUMBING
J 0
(-6050 5125);
DISPLAY 0.872340 (-6050 5125);
PAINT GREEN (-6050 5125);
DISPLAY INVISIBLE (-6050 5125);
FORCEPROP 1 LAST HDL_TAP TRUE
J 0
(-5725 4950);
DISPLAY 0.872340 (-5725 4950);
DISPLAY INVISIBLE (-5725 4950);
FORCEPROP 1 LAST PATH I442
J 0
(-6052 5075);
DISPLAY 0.872340 (-6052 5075);
PAINT GREEN (-6052 5075);
DISPLAY INVISIBLE (-6052 5075);
FORCEADD TAP..1
(-6050 5325);
FORCEPROP 3 LASTPIN (-6100 5325) SIG_NAME M_A_CPU0_SA_DQ<29>
J 0
(-6090 5335);
DISPLAY 0.659574 (-6090 5335);
PAINT MONO (-6090 5335);
DISPLAY INVISIBLE (-6090 5335);
FORCEPROP 1 LASTPIN (-6100 5325) BN 29
J 0
(-6112 5333);
DISPLAY 0.489362 (-6112 5333);
PAINT GREEN (-6112 5333);
FORCEPROP 2 LAST CDS_LIB mstr_standard
J 0
(-6050 5325);
DISPLAY 0.723404 (-6050 5325);
PAINT MONO (-6050 5325);
DISPLAY INVISIBLE (-6050 5325);
FORCEPROP 1 LAST BODY_TYPE PLUMBING
J 0
(-6050 5375);
DISPLAY 0.872340 (-6050 5375);
PAINT GREEN (-6050 5375);
DISPLAY INVISIBLE (-6050 5375);
FORCEPROP 1 LAST HDL_TAP TRUE
J 0
(-5725 5200);
DISPLAY 0.872340 (-5725 5200);
DISPLAY INVISIBLE (-5725 5200);
FORCEPROP 1 LAST PATH I443
J 0
(-6052 5325);
DISPLAY 0.872340 (-6052 5325);
PAINT GREEN (-6052 5325);
DISPLAY INVISIBLE (-6052 5325);
FORCEADD TAP..1
(-6050 5375);
FORCEPROP 3 LASTPIN (-6100 5375) SIG_NAME M_A_CPU0_SA_DQ<30>
J 0
(-6090 5385);
DISPLAY 0.659574 (-6090 5385);
PAINT MONO (-6090 5385);
DISPLAY INVISIBLE (-6090 5385);
FORCEPROP 1 LASTPIN (-6100 5375) BN 30
J 0
(-6112 5383);
DISPLAY 0.489362 (-6112 5383);
PAINT GREEN (-6112 5383);
FORCEPROP 2 LAST CDS_LIB mstr_standard
J 0
(-6050 5375);
DISPLAY 0.723404 (-6050 5375);
PAINT MONO (-6050 5375);
DISPLAY INVISIBLE (-6050 5375);
FORCEPROP 1 LAST BODY_TYPE PLUMBING
J 0
(-6050 5425);
DISPLAY 0.872340 (-6050 5425);
PAINT GREEN (-6050 5425);
DISPLAY INVISIBLE (-6050 5425);
FORCEPROP 1 LAST HDL_TAP TRUE
J 0
(-5725 5250);
DISPLAY 0.872340 (-5725 5250);
DISPLAY INVISIBLE (-5725 5250);
FORCEPROP 1 LAST PATH I444
J 0
(-6052 5375);
DISPLAY 0.872340 (-6052 5375);
PAINT GREEN (-6052 5375);
DISPLAY INVISIBLE (-6052 5375);
FORCEADD TAP..1
(-6050 5425);
FORCEPROP 3 LASTPIN (-6100 5425) SIG_NAME M_A_CPU0_SA_DQ<31>
J 0
(-6090 5435);
DISPLAY 0.659574 (-6090 5435);
PAINT MONO (-6090 5435);
DISPLAY INVISIBLE (-6090 5435);
FORCEPROP 1 LASTPIN (-6100 5425) BN 31
J 0
(-6112 5433);
DISPLAY 0.489362 (-6112 5433);
PAINT GREEN (-6112 5433);
FORCEPROP 2 LAST CDS_LIB mstr_standard
J 0
(-6050 5425);
DISPLAY 0.723404 (-6050 5425);
PAINT MONO (-6050 5425);
DISPLAY INVISIBLE (-6050 5425);
FORCEPROP 1 LAST BODY_TYPE PLUMBING
J 0
(-6050 5475);
DISPLAY 0.872340 (-6050 5475);
PAINT GREEN (-6050 5475);
DISPLAY INVISIBLE (-6050 5475);
FORCEPROP 1 LAST HDL_TAP TRUE
J 0
(-5725 5300);
DISPLAY 0.872340 (-5725 5300);
DISPLAY INVISIBLE (-5725 5300);
FORCEPROP 1 LAST PATH I445
J 0
(-6052 5425);
DISPLAY 0.872340 (-6052 5425);
PAINT GREEN (-6052 5425);
DISPLAY INVISIBLE (-6052 5425);
FORCEADD TAP..1
(-6050 5225);
FORCEPROP 3 LASTPIN (-6100 5225) SIG_NAME M_A_CPU0_SA_DQ<27>
J 0
(-6090 5235);
DISPLAY 0.659574 (-6090 5235);
PAINT MONO (-6090 5235);
DISPLAY INVISIBLE (-6090 5235);
FORCEPROP 1 LASTPIN (-6100 5225) BN 27
J 0
(-6112 5233);
DISPLAY 0.489362 (-6112 5233);
PAINT GREEN (-6112 5233);
FORCEPROP 2 LAST CDS_LIB mstr_standard
J 0
(-6050 5225);
DISPLAY 0.723404 (-6050 5225);
PAINT MONO (-6050 5225);
DISPLAY INVISIBLE (-6050 5225);
FORCEPROP 1 LAST BODY_TYPE PLUMBING
J 0
(-6050 5275);
DISPLAY 0.872340 (-6050 5275);
PAINT GREEN (-6050 5275);
DISPLAY INVISIBLE (-6050 5275);
FORCEPROP 1 LAST HDL_TAP TRUE
J 0
(-5725 5100);
DISPLAY 0.872340 (-5725 5100);
DISPLAY INVISIBLE (-5725 5100);
FORCEPROP 1 LAST PATH I446
J 0
(-6052 5225);
DISPLAY 0.872340 (-6052 5225);
PAINT GREEN (-6052 5225);
DISPLAY INVISIBLE (-6052 5225);
FORCEADD TAP..1
(-6050 5275);
FORCEPROP 3 LASTPIN (-6100 5275) SIG_NAME M_A_CPU0_SA_DQ<28>
J 0
(-6090 5285);
DISPLAY 0.659574 (-6090 5285);
PAINT MONO (-6090 5285);
DISPLAY INVISIBLE (-6090 5285);
FORCEPROP 1 LASTPIN (-6100 5275) BN 28
J 0
(-6112 5283);
DISPLAY 0.489362 (-6112 5283);
PAINT GREEN (-6112 5283);
FORCEPROP 2 LAST CDS_LIB mstr_standard
J 0
(-6050 5275);
DISPLAY 0.723404 (-6050 5275);
PAINT MONO (-6050 5275);
DISPLAY INVISIBLE (-6050 5275);
FORCEPROP 1 LAST BODY_TYPE PLUMBING
J 0
(-6050 5325);
DISPLAY 0.872340 (-6050 5325);
PAINT GREEN (-6050 5325);
DISPLAY INVISIBLE (-6050 5325);
FORCEPROP 1 LAST HDL_TAP TRUE
J 0
(-5725 5150);
DISPLAY 0.872340 (-5725 5150);
DISPLAY INVISIBLE (-5725 5150);
FORCEPROP 1 LAST PATH I447
J 0
(-6052 5275);
DISPLAY 0.872340 (-6052 5275);
PAINT GREEN (-6052 5275);
DISPLAY INVISIBLE (-6052 5275);
FORCEADD OFFPAGE..3
(-5500 5475);
FORCEPROP 2 LAST $XR0 10 
J 0
(-5286 5475);
DISPLAY 0.638298 (-5286 5475);
PAINT MONO (-5286 5475);
FORCEPROP 2 LAST PATH I448
J 0
(-5275 5525);
DISPLAY 0.808511 (-5275 5525);
DISPLAY INVISIBLE (-5275 5525);
FORCEPROP 1 LAST COMMENT_BODY TRUE
J 0
(-5550 5375);
DISPLAY 0.872340 (-5550 5375);
PAINT GREEN (-5550 5375);
DISPLAY INVISIBLE (-5550 5375);
FORCEPROP 1 LAST OFFPAGE TRUE
J 0
(-5175 5350);
DISPLAY 0.872340 (-5175 5350);
PAINT GREEN (-5175 5350);
DISPLAY INVISIBLE (-5175 5350);
FORCEPROP 2 LAST CDS_LIB mstr_standard
J 0
(-5500 5475);
DISPLAY 0.723404 (-5500 5475);
PAINT MONO (-5500 5475);
DISPLAY INVISIBLE (-5500 5475);
FORCEADD TAP..1
(-3600 3425);
FORCEPROP 3 LASTPIN (-3650 3425) SIG_NAME M_A_CPU0_SB_DQS_DP<0>
J 0
(-3640 3435);
DISPLAY 0.659574 (-3640 3435);
PAINT MONO (-3640 3435);
DISPLAY INVISIBLE (-3640 3435);
FORCEPROP 1 LASTPIN (-3650 3425) BN 0
J 0
(-3662 3433);
DISPLAY 0.489362 (-3662 3433);
PAINT GREEN (-3662 3433);
FORCEPROP 2 LAST CDS_LIB mstr_standard
J 0
(-3600 3425);
DISPLAY 0.723404 (-3600 3425);
PAINT MONO (-3600 3425);
DISPLAY INVISIBLE (-3600 3425);
FORCEPROP 1 LAST BODY_TYPE PLUMBING
J 0
(-3600 3475);
DISPLAY 0.872340 (-3600 3475);
PAINT GREEN (-3600 3475);
DISPLAY INVISIBLE (-3600 3475);
FORCEPROP 1 LAST HDL_TAP TRUE
J 0
(-3275 3300);
DISPLAY 0.872340 (-3275 3300);
DISPLAY INVISIBLE (-3275 3300);
FORCEPROP 1 LAST PATH I449
J 0
(-3602 3425);
DISPLAY 0.872340 (-3602 3425);
PAINT GREEN (-3602 3425);
DISPLAY INVISIBLE (-3602 3425);
FORCEADD TAP..1
(-3600 3525);
FORCEPROP 3 LASTPIN (-3650 3525) SIG_NAME M_A_CPU0_SB_DQS_DP<1>
J 0
(-3640 3535);
DISPLAY 0.659574 (-3640 3535);
PAINT MONO (-3640 3535);
DISPLAY INVISIBLE (-3640 3535);
FORCEPROP 1 LASTPIN (-3650 3525) BN 1
J 0
(-3662 3533);
DISPLAY 0.489362 (-3662 3533);
PAINT GREEN (-3662 3533);
FORCEPROP 2 LAST CDS_LIB mstr_standard
J 0
(-3600 3525);
DISPLAY 0.723404 (-3600 3525);
PAINT MONO (-3600 3525);
DISPLAY INVISIBLE (-3600 3525);
FORCEPROP 1 LAST BODY_TYPE PLUMBING
J 0
(-3600 3575);
DISPLAY 0.872340 (-3600 3575);
PAINT GREEN (-3600 3575);
DISPLAY INVISIBLE (-3600 3575);
FORCEPROP 1 LAST HDL_TAP TRUE
J 0
(-3275 3400);
DISPLAY 0.872340 (-3275 3400);
DISPLAY INVISIBLE (-3275 3400);
FORCEPROP 1 LAST PATH I450
J 0
(-3602 3525);
DISPLAY 0.872340 (-3602 3525);
PAINT GREEN (-3602 3525);
DISPLAY INVISIBLE (-3602 3525);
FORCEADD TAP..1
(-3400 3575);
FORCEPROP 3 LASTPIN (-3450 3575) SIG_NAME M_A_CPU0_SB_DQS_DN<2>
J 0
(-3440 3585);
DISPLAY 0.659574 (-3440 3585);
PAINT MONO (-3440 3585);
DISPLAY INVISIBLE (-3440 3585);
FORCEPROP 1 LASTPIN (-3450 3575) BN 2
J 0
(-3462 3583);
DISPLAY 0.489362 (-3462 3583);
PAINT GREEN (-3462 3583);
FORCEPROP 2 LAST CDS_LIB mstr_standard
J 0
(-3400 3575);
DISPLAY 0.723404 (-3400 3575);
PAINT MONO (-3400 3575);
DISPLAY INVISIBLE (-3400 3575);
FORCEPROP 1 LAST BODY_TYPE PLUMBING
J 0
(-3400 3625);
DISPLAY 0.872340 (-3400 3625);
PAINT GREEN (-3400 3625);
DISPLAY INVISIBLE (-3400 3625);
FORCEPROP 1 LAST HDL_TAP TRUE
J 0
(-3075 3450);
DISPLAY 0.872340 (-3075 3450);
DISPLAY INVISIBLE (-3075 3450);
FORCEPROP 1 LAST PATH I451
J 0
(-3402 3575);
DISPLAY 0.872340 (-3402 3575);
PAINT GREEN (-3402 3575);
DISPLAY INVISIBLE (-3402 3575);
FORCEADD TAP..1
(-3400 3475);
FORCEPROP 3 LASTPIN (-3450 3475) SIG_NAME M_A_CPU0_SB_DQS_DN<1>
J 0
(-3440 3485);
DISPLAY 0.659574 (-3440 3485);
PAINT MONO (-3440 3485);
DISPLAY INVISIBLE (-3440 3485);
FORCEPROP 1 LASTPIN (-3450 3475) BN 1
J 0
(-3462 3483);
DISPLAY 0.489362 (-3462 3483);
PAINT GREEN (-3462 3483);
FORCEPROP 2 LAST CDS_LIB mstr_standard
J 0
(-3400 3475);
DISPLAY 0.723404 (-3400 3475);
PAINT MONO (-3400 3475);
DISPLAY INVISIBLE (-3400 3475);
FORCEPROP 1 LAST BODY_TYPE PLUMBING
J 0
(-3400 3525);
DISPLAY 0.872340 (-3400 3525);
PAINT GREEN (-3400 3525);
DISPLAY INVISIBLE (-3400 3525);
FORCEPROP 1 LAST HDL_TAP TRUE
J 0
(-3075 3350);
DISPLAY 0.872340 (-3075 3350);
DISPLAY INVISIBLE (-3075 3350);
FORCEPROP 1 LAST PATH I452
J 0
(-3402 3475);
DISPLAY 0.872340 (-3402 3475);
PAINT GREEN (-3402 3475);
DISPLAY INVISIBLE (-3402 3475);
FORCEADD TAP..1
(-3400 3375);
FORCEPROP 3 LASTPIN (-3450 3375) SIG_NAME M_A_CPU0_SB_DQS_DN<0>
J 0
(-3440 3385);
DISPLAY 0.659574 (-3440 3385);
PAINT MONO (-3440 3385);
DISPLAY INVISIBLE (-3440 3385);
FORCEPROP 1 LASTPIN (-3450 3375) BN 0
J 0
(-3462 3383);
DISPLAY 0.489362 (-3462 3383);
PAINT GREEN (-3462 3383);
FORCEPROP 2 LAST CDS_LIB mstr_standard
J 0
(-3400 3375);
DISPLAY 0.723404 (-3400 3375);
PAINT MONO (-3400 3375);
DISPLAY INVISIBLE (-3400 3375);
FORCEPROP 1 LAST BODY_TYPE PLUMBING
J 0
(-3400 3425);
DISPLAY 0.872340 (-3400 3425);
PAINT GREEN (-3400 3425);
DISPLAY INVISIBLE (-3400 3425);
FORCEPROP 1 LAST HDL_TAP TRUE
J 0
(-3075 3250);
DISPLAY 0.872340 (-3075 3250);
DISPLAY INVISIBLE (-3075 3250);
FORCEPROP 1 LAST PATH I453
J 0
(-3402 3375);
DISPLAY 0.872340 (-3402 3375);
PAINT GREEN (-3402 3375);
DISPLAY INVISIBLE (-3402 3375);
FORCEADD TAP..1
(-3600 3625);
FORCEPROP 3 LASTPIN (-3650 3625) SIG_NAME M_A_CPU0_SB_DQS_DP<2>
J 0
(-3640 3635);
DISPLAY 0.659574 (-3640 3635);
PAINT MONO (-3640 3635);
DISPLAY INVISIBLE (-3640 3635);
FORCEPROP 1 LASTPIN (-3650 3625) BN 2
J 0
(-3662 3633);
DISPLAY 0.489362 (-3662 3633);
PAINT GREEN (-3662 3633);
FORCEPROP 2 LAST CDS_LIB mstr_standard
J 0
(-3600 3625);
DISPLAY 0.723404 (-3600 3625);
PAINT MONO (-3600 3625);
DISPLAY INVISIBLE (-3600 3625);
FORCEPROP 1 LAST BODY_TYPE PLUMBING
J 0
(-3600 3675);
DISPLAY 0.872340 (-3600 3675);
PAINT GREEN (-3600 3675);
DISPLAY INVISIBLE (-3600 3675);
FORCEPROP 1 LAST HDL_TAP TRUE
J 0
(-3275 3500);
DISPLAY 0.872340 (-3275 3500);
DISPLAY INVISIBLE (-3275 3500);
FORCEPROP 1 LAST PATH I454
J 0
(-3602 3625);
DISPLAY 0.872340 (-3602 3625);
PAINT GREEN (-3602 3625);
DISPLAY INVISIBLE (-3602 3625);
FORCEADD TAP..1
(-3600 3725);
FORCEPROP 3 LASTPIN (-3650 3725) SIG_NAME M_A_CPU0_SB_DQS_DP<3>
J 0
(-3640 3735);
DISPLAY 0.659574 (-3640 3735);
PAINT MONO (-3640 3735);
DISPLAY INVISIBLE (-3640 3735);
FORCEPROP 1 LASTPIN (-3650 3725) BN 3
J 0
(-3662 3733);
DISPLAY 0.489362 (-3662 3733);
PAINT GREEN (-3662 3733);
FORCEPROP 2 LAST CDS_LIB mstr_standard
J 0
(-3600 3725);
DISPLAY 0.723404 (-3600 3725);
PAINT MONO (-3600 3725);
DISPLAY INVISIBLE (-3600 3725);
FORCEPROP 1 LAST BODY_TYPE PLUMBING
J 0
(-3600 3775);
DISPLAY 0.872340 (-3600 3775);
PAINT GREEN (-3600 3775);
DISPLAY INVISIBLE (-3600 3775);
FORCEPROP 1 LAST HDL_TAP TRUE
J 0
(-3275 3600);
DISPLAY 0.872340 (-3275 3600);
DISPLAY INVISIBLE (-3275 3600);
FORCEPROP 1 LAST PATH I455
J 0
(-3602 3725);
DISPLAY 0.872340 (-3602 3725);
PAINT GREEN (-3602 3725);
DISPLAY INVISIBLE (-3602 3725);
FORCEADD TAP..1
(-3600 3825);
FORCEPROP 3 LASTPIN (-3650 3825) SIG_NAME M_A_CPU0_SB_DQS_DP<4>
J 0
(-3640 3835);
DISPLAY 0.659574 (-3640 3835);
PAINT MONO (-3640 3835);
DISPLAY INVISIBLE (-3640 3835);
FORCEPROP 1 LASTPIN (-3650 3825) BN 4
J 0
(-3662 3833);
DISPLAY 0.489362 (-3662 3833);
PAINT GREEN (-3662 3833);
FORCEPROP 2 LAST CDS_LIB mstr_standard
J 0
(-3600 3825);
DISPLAY 0.723404 (-3600 3825);
PAINT MONO (-3600 3825);
DISPLAY INVISIBLE (-3600 3825);
FORCEPROP 1 LAST BODY_TYPE PLUMBING
J 0
(-3600 3875);
DISPLAY 0.872340 (-3600 3875);
PAINT GREEN (-3600 3875);
DISPLAY INVISIBLE (-3600 3875);
FORCEPROP 1 LAST HDL_TAP TRUE
J 0
(-3275 3700);
DISPLAY 0.872340 (-3275 3700);
DISPLAY INVISIBLE (-3275 3700);
FORCEPROP 1 LAST PATH I456
J 0
(-3602 3825);
DISPLAY 0.872340 (-3602 3825);
PAINT GREEN (-3602 3825);
DISPLAY INVISIBLE (-3602 3825);
FORCEADD TAP..1
(-3400 3675);
FORCEPROP 3 LASTPIN (-3450 3675) SIG_NAME M_A_CPU0_SB_DQS_DN<3>
J 0
(-3440 3685);
DISPLAY 0.659574 (-3440 3685);
PAINT MONO (-3440 3685);
DISPLAY INVISIBLE (-3440 3685);
FORCEPROP 1 LASTPIN (-3450 3675) BN 3
J 0
(-3462 3683);
DISPLAY 0.489362 (-3462 3683);
PAINT GREEN (-3462 3683);
FORCEPROP 2 LAST CDS_LIB mstr_standard
J 0
(-3400 3675);
DISPLAY 0.723404 (-3400 3675);
PAINT MONO (-3400 3675);
DISPLAY INVISIBLE (-3400 3675);
FORCEPROP 1 LAST BODY_TYPE PLUMBING
J 0
(-3400 3725);
DISPLAY 0.872340 (-3400 3725);
PAINT GREEN (-3400 3725);
DISPLAY INVISIBLE (-3400 3725);
FORCEPROP 1 LAST HDL_TAP TRUE
J 0
(-3075 3550);
DISPLAY 0.872340 (-3075 3550);
DISPLAY INVISIBLE (-3075 3550);
FORCEPROP 1 LAST PATH I457
J 0
(-3402 3675);
DISPLAY 0.872340 (-3402 3675);
PAINT GREEN (-3402 3675);
DISPLAY INVISIBLE (-3402 3675);
FORCEADD TAP..1
(-3400 3775);
FORCEPROP 3 LASTPIN (-3450 3775) SIG_NAME M_A_CPU0_SB_DQS_DN<4>
J 0
(-3440 3785);
DISPLAY 0.659574 (-3440 3785);
PAINT MONO (-3440 3785);
DISPLAY INVISIBLE (-3440 3785);
FORCEPROP 1 LASTPIN (-3450 3775) BN 4
J 0
(-3462 3783);
DISPLAY 0.489362 (-3462 3783);
PAINT GREEN (-3462 3783);
FORCEPROP 2 LAST CDS_LIB mstr_standard
J 0
(-3400 3775);
DISPLAY 0.723404 (-3400 3775);
PAINT MONO (-3400 3775);
DISPLAY INVISIBLE (-3400 3775);
FORCEPROP 1 LAST BODY_TYPE PLUMBING
J 0
(-3400 3825);
DISPLAY 0.872340 (-3400 3825);
PAINT GREEN (-3400 3825);
DISPLAY INVISIBLE (-3400 3825);
FORCEPROP 1 LAST HDL_TAP TRUE
J 0
(-3075 3650);
DISPLAY 0.872340 (-3075 3650);
DISPLAY INVISIBLE (-3075 3650);
FORCEPROP 1 LAST PATH I458
J 0
(-3402 3775);
DISPLAY 0.872340 (-3402 3775);
PAINT GREEN (-3402 3775);
DISPLAY INVISIBLE (-3402 3775);
FORCEADD TAP..1
(-3600 3925);
FORCEPROP 3 LASTPIN (-3650 3925) SIG_NAME M_A_CPU0_SB_DQS_DP<5>
J 0
(-3640 3935);
DISPLAY 0.659574 (-3640 3935);
PAINT MONO (-3640 3935);
DISPLAY INVISIBLE (-3640 3935);
FORCEPROP 1 LASTPIN (-3650 3925) BN 5
J 0
(-3662 3933);
DISPLAY 0.489362 (-3662 3933);
PAINT GREEN (-3662 3933);
FORCEPROP 2 LAST CDS_LIB mstr_standard
J 0
(-3600 3925);
DISPLAY 0.723404 (-3600 3925);
PAINT MONO (-3600 3925);
DISPLAY INVISIBLE (-3600 3925);
FORCEPROP 1 LAST BODY_TYPE PLUMBING
J 0
(-3600 3975);
DISPLAY 0.872340 (-3600 3975);
PAINT GREEN (-3600 3975);
DISPLAY INVISIBLE (-3600 3975);
FORCEPROP 1 LAST HDL_TAP TRUE
J 0
(-3275 3800);
DISPLAY 0.872340 (-3275 3800);
DISPLAY INVISIBLE (-3275 3800);
FORCEPROP 1 LAST PATH I459
J 0
(-3602 3925);
DISPLAY 0.872340 (-3602 3925);
PAINT GREEN (-3602 3925);
DISPLAY INVISIBLE (-3602 3925);
FORCEADD TAP..1
(-3600 4025);
FORCEPROP 3 LASTPIN (-3650 4025) SIG_NAME M_A_CPU0_SB_DQS_DP<6>
J 0
(-3640 4035);
DISPLAY 0.659574 (-3640 4035);
PAINT MONO (-3640 4035);
DISPLAY INVISIBLE (-3640 4035);
FORCEPROP 1 LASTPIN (-3650 4025) BN 6
J 0
(-3662 4033);
DISPLAY 0.489362 (-3662 4033);
PAINT GREEN (-3662 4033);
FORCEPROP 2 LAST CDS_LIB mstr_standard
J 0
(-3600 4025);
DISPLAY 0.723404 (-3600 4025);
PAINT MONO (-3600 4025);
DISPLAY INVISIBLE (-3600 4025);
FORCEPROP 1 LAST BODY_TYPE PLUMBING
J 0
(-3600 4075);
DISPLAY 0.872340 (-3600 4075);
PAINT GREEN (-3600 4075);
DISPLAY INVISIBLE (-3600 4075);
FORCEPROP 1 LAST HDL_TAP TRUE
J 0
(-3275 3900);
DISPLAY 0.872340 (-3275 3900);
DISPLAY INVISIBLE (-3275 3900);
FORCEPROP 1 LAST PATH I460
J 0
(-3602 4025);
DISPLAY 0.872340 (-3602 4025);
PAINT GREEN (-3602 4025);
DISPLAY INVISIBLE (-3602 4025);
FORCEADD TAP..1
(-3400 4075);
FORCEPROP 3 LASTPIN (-3450 4075) SIG_NAME M_A_CPU0_SB_DQS_DN<7>
J 0
(-3440 4085);
DISPLAY 0.659574 (-3440 4085);
PAINT MONO (-3440 4085);
DISPLAY INVISIBLE (-3440 4085);
FORCEPROP 1 LASTPIN (-3450 4075) BN 7
J 0
(-3462 4083);
DISPLAY 0.489362 (-3462 4083);
PAINT GREEN (-3462 4083);
FORCEPROP 2 LAST CDS_LIB mstr_standard
J 0
(-3400 4075);
DISPLAY 0.723404 (-3400 4075);
PAINT MONO (-3400 4075);
DISPLAY INVISIBLE (-3400 4075);
FORCEPROP 1 LAST BODY_TYPE PLUMBING
J 0
(-3400 4125);
DISPLAY 0.872340 (-3400 4125);
PAINT GREEN (-3400 4125);
DISPLAY INVISIBLE (-3400 4125);
FORCEPROP 1 LAST HDL_TAP TRUE
J 0
(-3075 3950);
DISPLAY 0.872340 (-3075 3950);
DISPLAY INVISIBLE (-3075 3950);
FORCEPROP 1 LAST PATH I461
J 0
(-3402 4075);
DISPLAY 0.872340 (-3402 4075);
PAINT GREEN (-3402 4075);
DISPLAY INVISIBLE (-3402 4075);
FORCEADD TAP..1
(-3400 3975);
FORCEPROP 3 LASTPIN (-3450 3975) SIG_NAME M_A_CPU0_SB_DQS_DN<6>
J 0
(-3440 3985);
DISPLAY 0.659574 (-3440 3985);
PAINT MONO (-3440 3985);
DISPLAY INVISIBLE (-3440 3985);
FORCEPROP 1 LASTPIN (-3450 3975) BN 6
J 0
(-3462 3983);
DISPLAY 0.489362 (-3462 3983);
PAINT GREEN (-3462 3983);
FORCEPROP 2 LAST CDS_LIB mstr_standard
J 0
(-3400 3975);
DISPLAY 0.723404 (-3400 3975);
PAINT MONO (-3400 3975);
DISPLAY INVISIBLE (-3400 3975);
FORCEPROP 1 LAST BODY_TYPE PLUMBING
J 0
(-3400 4025);
DISPLAY 0.872340 (-3400 4025);
PAINT GREEN (-3400 4025);
DISPLAY INVISIBLE (-3400 4025);
FORCEPROP 1 LAST HDL_TAP TRUE
J 0
(-3075 3850);
DISPLAY 0.872340 (-3075 3850);
DISPLAY INVISIBLE (-3075 3850);
FORCEPROP 1 LAST PATH I462
J 0
(-3402 3975);
DISPLAY 0.872340 (-3402 3975);
PAINT GREEN (-3402 3975);
DISPLAY INVISIBLE (-3402 3975);
FORCEADD TAP..1
(-3400 3875);
FORCEPROP 3 LASTPIN (-3450 3875) SIG_NAME M_A_CPU0_SB_DQS_DN<5>
J 0
(-3440 3885);
DISPLAY 0.659574 (-3440 3885);
PAINT MONO (-3440 3885);
DISPLAY INVISIBLE (-3440 3885);
FORCEPROP 1 LASTPIN (-3450 3875) BN 5
J 0
(-3462 3883);
DISPLAY 0.489362 (-3462 3883);
PAINT GREEN (-3462 3883);
FORCEPROP 2 LAST CDS_LIB mstr_standard
J 0
(-3400 3875);
DISPLAY 0.723404 (-3400 3875);
PAINT MONO (-3400 3875);
DISPLAY INVISIBLE (-3400 3875);
FORCEPROP 1 LAST BODY_TYPE PLUMBING
J 0
(-3400 3925);
DISPLAY 0.872340 (-3400 3925);
PAINT GREEN (-3400 3925);
DISPLAY INVISIBLE (-3400 3925);
FORCEPROP 1 LAST HDL_TAP TRUE
J 0
(-3075 3750);
DISPLAY 0.872340 (-3075 3750);
DISPLAY INVISIBLE (-3075 3750);
FORCEPROP 1 LAST PATH I463
J 0
(-3402 3875);
DISPLAY 0.872340 (-3402 3875);
PAINT GREEN (-3402 3875);
DISPLAY INVISIBLE (-3402 3875);
FORCEADD TAP..1
(-3600 4125);
FORCEPROP 3 LASTPIN (-3650 4125) SIG_NAME M_A_CPU0_SB_DQS_DP<7>
J 0
(-3640 4135);
DISPLAY 0.659574 (-3640 4135);
PAINT MONO (-3640 4135);
DISPLAY INVISIBLE (-3640 4135);
FORCEPROP 1 LASTPIN (-3650 4125) BN 7
J 0
(-3662 4133);
DISPLAY 0.489362 (-3662 4133);
PAINT GREEN (-3662 4133);
FORCEPROP 2 LAST CDS_LIB mstr_standard
J 0
(-3600 4125);
DISPLAY 0.723404 (-3600 4125);
PAINT MONO (-3600 4125);
DISPLAY INVISIBLE (-3600 4125);
FORCEPROP 1 LAST BODY_TYPE PLUMBING
J 0
(-3600 4175);
DISPLAY 0.872340 (-3600 4175);
PAINT GREEN (-3600 4175);
DISPLAY INVISIBLE (-3600 4175);
FORCEPROP 1 LAST HDL_TAP TRUE
J 0
(-3275 4000);
DISPLAY 0.872340 (-3275 4000);
DISPLAY INVISIBLE (-3275 4000);
FORCEPROP 1 LAST PATH I464
J 0
(-3602 4125);
DISPLAY 0.872340 (-3602 4125);
PAINT GREEN (-3602 4125);
DISPLAY INVISIBLE (-3602 4125);
FORCEADD TAP..1
(-3600 4225);
FORCEPROP 3 LASTPIN (-3650 4225) SIG_NAME M_A_CPU0_SB_DQS_DP<8>
J 0
(-3640 4235);
DISPLAY 0.659574 (-3640 4235);
PAINT MONO (-3640 4235);
DISPLAY INVISIBLE (-3640 4235);
FORCEPROP 1 LASTPIN (-3650 4225) BN 8
J 0
(-3662 4233);
DISPLAY 0.489362 (-3662 4233);
PAINT GREEN (-3662 4233);
FORCEPROP 2 LAST CDS_LIB mstr_standard
J 0
(-3600 4225);
DISPLAY 0.723404 (-3600 4225);
PAINT MONO (-3600 4225);
DISPLAY INVISIBLE (-3600 4225);
FORCEPROP 1 LAST BODY_TYPE PLUMBING
J 0
(-3600 4275);
DISPLAY 0.872340 (-3600 4275);
PAINT GREEN (-3600 4275);
DISPLAY INVISIBLE (-3600 4275);
FORCEPROP 1 LAST HDL_TAP TRUE
J 0
(-3275 4100);
DISPLAY 0.872340 (-3275 4100);
DISPLAY INVISIBLE (-3275 4100);
FORCEPROP 1 LAST PATH I465
J 0
(-3602 4225);
DISPLAY 0.872340 (-3602 4225);
PAINT GREEN (-3602 4225);
DISPLAY INVISIBLE (-3602 4225);
FORCEADD TAP..1
(-3600 4325);
FORCEPROP 3 LASTPIN (-3650 4325) SIG_NAME M_A_CPU0_SB_DQS_DP<9>
J 0
(-3640 4335);
DISPLAY 0.659574 (-3640 4335);
PAINT MONO (-3640 4335);
DISPLAY INVISIBLE (-3640 4335);
FORCEPROP 1 LASTPIN (-3650 4325) BN 9
J 0
(-3662 4333);
DISPLAY 0.489362 (-3662 4333);
PAINT GREEN (-3662 4333);
FORCEPROP 2 LAST CDS_LIB mstr_standard
J 0
(-3600 4325);
DISPLAY 0.723404 (-3600 4325);
PAINT MONO (-3600 4325);
DISPLAY INVISIBLE (-3600 4325);
FORCEPROP 1 LAST BODY_TYPE PLUMBING
J 0
(-3600 4375);
DISPLAY 0.872340 (-3600 4375);
PAINT GREEN (-3600 4375);
DISPLAY INVISIBLE (-3600 4375);
FORCEPROP 1 LAST HDL_TAP TRUE
J 0
(-3275 4200);
DISPLAY 0.872340 (-3275 4200);
DISPLAY INVISIBLE (-3275 4200);
FORCEPROP 1 LAST PATH I466
J 0
(-3602 4325);
DISPLAY 0.872340 (-3602 4325);
PAINT GREEN (-3602 4325);
DISPLAY INVISIBLE (-3602 4325);
FORCEADD TAP..1
(-3400 4175);
FORCEPROP 3 LASTPIN (-3450 4175) SIG_NAME M_A_CPU0_SB_DQS_DN<8>
J 0
(-3440 4185);
DISPLAY 0.659574 (-3440 4185);
PAINT MONO (-3440 4185);
DISPLAY INVISIBLE (-3440 4185);
FORCEPROP 1 LASTPIN (-3450 4175) BN 8
J 0
(-3462 4183);
DISPLAY 0.489362 (-3462 4183);
PAINT GREEN (-3462 4183);
FORCEPROP 2 LAST CDS_LIB mstr_standard
J 0
(-3400 4175);
DISPLAY 0.723404 (-3400 4175);
PAINT MONO (-3400 4175);
DISPLAY INVISIBLE (-3400 4175);
FORCEPROP 1 LAST BODY_TYPE PLUMBING
J 0
(-3400 4225);
DISPLAY 0.872340 (-3400 4225);
PAINT GREEN (-3400 4225);
DISPLAY INVISIBLE (-3400 4225);
FORCEPROP 1 LAST HDL_TAP TRUE
J 0
(-3075 4050);
DISPLAY 0.872340 (-3075 4050);
DISPLAY INVISIBLE (-3075 4050);
FORCEPROP 1 LAST PATH I467
J 0
(-3402 4175);
DISPLAY 0.872340 (-3402 4175);
PAINT GREEN (-3402 4175);
DISPLAY INVISIBLE (-3402 4175);
FORCEADD TAP..1
(-3400 4275);
FORCEPROP 3 LASTPIN (-3450 4275) SIG_NAME M_A_CPU0_SB_DQS_DN<9>
J 0
(-3440 4285);
DISPLAY 0.659574 (-3440 4285);
PAINT MONO (-3440 4285);
DISPLAY INVISIBLE (-3440 4285);
FORCEPROP 1 LASTPIN (-3450 4275) BN 9
J 0
(-3462 4283);
DISPLAY 0.489362 (-3462 4283);
PAINT GREEN (-3462 4283);
FORCEPROP 2 LAST CDS_LIB mstr_standard
J 0
(-3400 4275);
DISPLAY 0.723404 (-3400 4275);
PAINT MONO (-3400 4275);
DISPLAY INVISIBLE (-3400 4275);
FORCEPROP 1 LAST BODY_TYPE PLUMBING
J 0
(-3400 4325);
DISPLAY 0.872340 (-3400 4325);
PAINT GREEN (-3400 4325);
DISPLAY INVISIBLE (-3400 4325);
FORCEPROP 1 LAST HDL_TAP TRUE
J 0
(-3075 4150);
DISPLAY 0.872340 (-3075 4150);
DISPLAY INVISIBLE (-3075 4150);
FORCEPROP 1 LAST PATH I468
J 0
(-3402 4275);
DISPLAY 0.872340 (-3402 4275);
PAINT GREEN (-3402 4275);
DISPLAY INVISIBLE (-3402 4275);
FORCEADD TAP..1
(-3600 4475);
FORCEPROP 3 LASTPIN (-3650 4475) SIG_NAME M_A_CPU0_SA_DQS_DP<0>
J 0
(-3640 4485);
DISPLAY 0.659574 (-3640 4485);
PAINT MONO (-3640 4485);
DISPLAY INVISIBLE (-3640 4485);
FORCEPROP 1 LASTPIN (-3650 4475) BN 0
J 0
(-3662 4483);
DISPLAY 0.489362 (-3662 4483);
PAINT GREEN (-3662 4483);
FORCEPROP 2 LAST CDS_LIB mstr_standard
J 0
(-3600 4475);
DISPLAY 0.723404 (-3600 4475);
PAINT MONO (-3600 4475);
DISPLAY INVISIBLE (-3600 4475);
FORCEPROP 1 LAST BODY_TYPE PLUMBING
J 0
(-3600 4525);
DISPLAY 0.872340 (-3600 4525);
PAINT GREEN (-3600 4525);
DISPLAY INVISIBLE (-3600 4525);
FORCEPROP 1 LAST HDL_TAP TRUE
J 0
(-3275 4350);
DISPLAY 0.872340 (-3275 4350);
DISPLAY INVISIBLE (-3275 4350);
FORCEPROP 1 LAST PATH I469
J 0
(-3602 4475);
DISPLAY 0.872340 (-3602 4475);
PAINT GREEN (-3602 4475);
DISPLAY INVISIBLE (-3602 4475);
FORCEADD TAP..1
(-3600 4575);
FORCEPROP 3 LASTPIN (-3650 4575) SIG_NAME M_A_CPU0_SA_DQS_DP<1>
J 0
(-3640 4585);
DISPLAY 0.659574 (-3640 4585);
PAINT MONO (-3640 4585);
DISPLAY INVISIBLE (-3640 4585);
FORCEPROP 1 LASTPIN (-3650 4575) BN 1
J 0
(-3662 4583);
DISPLAY 0.489362 (-3662 4583);
PAINT GREEN (-3662 4583);
FORCEPROP 2 LAST CDS_LIB mstr_standard
J 0
(-3600 4575);
DISPLAY 0.723404 (-3600 4575);
PAINT MONO (-3600 4575);
DISPLAY INVISIBLE (-3600 4575);
FORCEPROP 1 LAST BODY_TYPE PLUMBING
J 0
(-3600 4625);
DISPLAY 0.872340 (-3600 4625);
PAINT GREEN (-3600 4625);
DISPLAY INVISIBLE (-3600 4625);
FORCEPROP 1 LAST HDL_TAP TRUE
J 0
(-3275 4450);
DISPLAY 0.872340 (-3275 4450);
DISPLAY INVISIBLE (-3275 4450);
FORCEPROP 1 LAST PATH I470
J 0
(-3602 4575);
DISPLAY 0.872340 (-3602 4575);
PAINT GREEN (-3602 4575);
DISPLAY INVISIBLE (-3602 4575);
FORCEADD TAP..1
(-3400 4425);
FORCEPROP 3 LASTPIN (-3450 4425) SIG_NAME M_A_CPU0_SA_DQS_DN<0>
J 0
(-3440 4435);
DISPLAY 0.659574 (-3440 4435);
PAINT MONO (-3440 4435);
DISPLAY INVISIBLE (-3440 4435);
FORCEPROP 1 LASTPIN (-3450 4425) BN 0
J 0
(-3462 4433);
DISPLAY 0.489362 (-3462 4433);
PAINT GREEN (-3462 4433);
FORCEPROP 2 LAST CDS_LIB mstr_standard
J 0
(-3400 4425);
DISPLAY 0.723404 (-3400 4425);
PAINT MONO (-3400 4425);
DISPLAY INVISIBLE (-3400 4425);
FORCEPROP 1 LAST BODY_TYPE PLUMBING
J 0
(-3400 4475);
DISPLAY 0.872340 (-3400 4475);
PAINT GREEN (-3400 4475);
DISPLAY INVISIBLE (-3400 4475);
FORCEPROP 1 LAST HDL_TAP TRUE
J 0
(-3075 4300);
DISPLAY 0.872340 (-3075 4300);
DISPLAY INVISIBLE (-3075 4300);
FORCEPROP 1 LAST PATH I471
J 0
(-3402 4425);
DISPLAY 0.872340 (-3402 4425);
PAINT GREEN (-3402 4425);
DISPLAY INVISIBLE (-3402 4425);
FORCEADD TAP..1
(-3400 4525);
FORCEPROP 3 LASTPIN (-3450 4525) SIG_NAME M_A_CPU0_SA_DQS_DN<1>
J 0
(-3440 4535);
DISPLAY 0.659574 (-3440 4535);
PAINT MONO (-3440 4535);
DISPLAY INVISIBLE (-3440 4535);
FORCEPROP 1 LASTPIN (-3450 4525) BN 1
J 0
(-3462 4533);
DISPLAY 0.489362 (-3462 4533);
PAINT GREEN (-3462 4533);
FORCEPROP 2 LAST CDS_LIB mstr_standard
J 0
(-3400 4525);
DISPLAY 0.723404 (-3400 4525);
PAINT MONO (-3400 4525);
DISPLAY INVISIBLE (-3400 4525);
FORCEPROP 1 LAST BODY_TYPE PLUMBING
J 0
(-3400 4575);
DISPLAY 0.872340 (-3400 4575);
PAINT GREEN (-3400 4575);
DISPLAY INVISIBLE (-3400 4575);
FORCEPROP 1 LAST HDL_TAP TRUE
J 0
(-3075 4400);
DISPLAY 0.872340 (-3075 4400);
DISPLAY INVISIBLE (-3075 4400);
FORCEPROP 1 LAST PATH I472
J 0
(-3402 4525);
DISPLAY 0.872340 (-3402 4525);
PAINT GREEN (-3402 4525);
DISPLAY INVISIBLE (-3402 4525);
FORCEADD TAP..1
(-3600 4675);
FORCEPROP 3 LASTPIN (-3650 4675) SIG_NAME M_A_CPU0_SA_DQS_DP<2>
J 0
(-3640 4685);
DISPLAY 0.659574 (-3640 4685);
PAINT MONO (-3640 4685);
DISPLAY INVISIBLE (-3640 4685);
FORCEPROP 1 LASTPIN (-3650 4675) BN 2
J 0
(-3662 4683);
DISPLAY 0.489362 (-3662 4683);
PAINT GREEN (-3662 4683);
FORCEPROP 2 LAST CDS_LIB mstr_standard
J 0
(-3600 4675);
DISPLAY 0.723404 (-3600 4675);
PAINT MONO (-3600 4675);
DISPLAY INVISIBLE (-3600 4675);
FORCEPROP 1 LAST BODY_TYPE PLUMBING
J 0
(-3600 4725);
DISPLAY 0.872340 (-3600 4725);
PAINT GREEN (-3600 4725);
DISPLAY INVISIBLE (-3600 4725);
FORCEPROP 1 LAST HDL_TAP TRUE
J 0
(-3275 4550);
DISPLAY 0.872340 (-3275 4550);
DISPLAY INVISIBLE (-3275 4550);
FORCEPROP 1 LAST PATH I473
J 0
(-3602 4675);
DISPLAY 0.872340 (-3602 4675);
PAINT GREEN (-3602 4675);
DISPLAY INVISIBLE (-3602 4675);
FORCEADD TAP..1
(-3600 4775);
FORCEPROP 3 LASTPIN (-3650 4775) SIG_NAME M_A_CPU0_SA_DQS_DP<3>
J 0
(-3640 4785);
DISPLAY 0.659574 (-3640 4785);
PAINT MONO (-3640 4785);
DISPLAY INVISIBLE (-3640 4785);
FORCEPROP 1 LASTPIN (-3650 4775) BN 3
J 0
(-3662 4783);
DISPLAY 0.489362 (-3662 4783);
PAINT GREEN (-3662 4783);
FORCEPROP 2 LAST CDS_LIB mstr_standard
J 0
(-3600 4775);
DISPLAY 0.723404 (-3600 4775);
PAINT MONO (-3600 4775);
DISPLAY INVISIBLE (-3600 4775);
FORCEPROP 1 LAST BODY_TYPE PLUMBING
J 0
(-3600 4825);
DISPLAY 0.872340 (-3600 4825);
PAINT GREEN (-3600 4825);
DISPLAY INVISIBLE (-3600 4825);
FORCEPROP 1 LAST HDL_TAP TRUE
J 0
(-3275 4650);
DISPLAY 0.872340 (-3275 4650);
DISPLAY INVISIBLE (-3275 4650);
FORCEPROP 1 LAST PATH I474
J 0
(-3602 4775);
DISPLAY 0.872340 (-3602 4775);
PAINT GREEN (-3602 4775);
DISPLAY INVISIBLE (-3602 4775);
FORCEADD TAP..1
(-3400 4625);
FORCEPROP 3 LASTPIN (-3450 4625) SIG_NAME M_A_CPU0_SA_DQS_DN<2>
J 0
(-3440 4635);
DISPLAY 0.659574 (-3440 4635);
PAINT MONO (-3440 4635);
DISPLAY INVISIBLE (-3440 4635);
FORCEPROP 1 LASTPIN (-3450 4625) BN 2
J 0
(-3462 4633);
DISPLAY 0.489362 (-3462 4633);
PAINT GREEN (-3462 4633);
FORCEPROP 2 LAST CDS_LIB mstr_standard
J 0
(-3400 4625);
DISPLAY 0.723404 (-3400 4625);
PAINT MONO (-3400 4625);
DISPLAY INVISIBLE (-3400 4625);
FORCEPROP 1 LAST BODY_TYPE PLUMBING
J 0
(-3400 4675);
DISPLAY 0.872340 (-3400 4675);
PAINT GREEN (-3400 4675);
DISPLAY INVISIBLE (-3400 4675);
FORCEPROP 1 LAST HDL_TAP TRUE
J 0
(-3075 4500);
DISPLAY 0.872340 (-3075 4500);
DISPLAY INVISIBLE (-3075 4500);
FORCEPROP 1 LAST PATH I475
J 0
(-3402 4625);
DISPLAY 0.872340 (-3402 4625);
PAINT GREEN (-3402 4625);
DISPLAY INVISIBLE (-3402 4625);
FORCEADD TAP..1
(-3400 4725);
FORCEPROP 3 LASTPIN (-3450 4725) SIG_NAME M_A_CPU0_SA_DQS_DN<3>
J 0
(-3440 4735);
DISPLAY 0.659574 (-3440 4735);
PAINT MONO (-3440 4735);
DISPLAY INVISIBLE (-3440 4735);
FORCEPROP 1 LASTPIN (-3450 4725) BN 3
J 0
(-3462 4733);
DISPLAY 0.489362 (-3462 4733);
PAINT GREEN (-3462 4733);
FORCEPROP 2 LAST CDS_LIB mstr_standard
J 0
(-3400 4725);
DISPLAY 0.723404 (-3400 4725);
PAINT MONO (-3400 4725);
DISPLAY INVISIBLE (-3400 4725);
FORCEPROP 1 LAST BODY_TYPE PLUMBING
J 0
(-3400 4775);
DISPLAY 0.872340 (-3400 4775);
PAINT GREEN (-3400 4775);
DISPLAY INVISIBLE (-3400 4775);
FORCEPROP 1 LAST HDL_TAP TRUE
J 0
(-3075 4600);
DISPLAY 0.872340 (-3075 4600);
DISPLAY INVISIBLE (-3075 4600);
FORCEPROP 1 LAST PATH I476
J 0
(-3402 4725);
DISPLAY 0.872340 (-3402 4725);
PAINT GREEN (-3402 4725);
DISPLAY INVISIBLE (-3402 4725);
FORCEADD TAP..1
(-3400 4825);
FORCEPROP 3 LASTPIN (-3450 4825) SIG_NAME M_A_CPU0_SA_DQS_DN<4>
J 0
(-3440 4835);
DISPLAY 0.659574 (-3440 4835);
PAINT MONO (-3440 4835);
DISPLAY INVISIBLE (-3440 4835);
FORCEPROP 1 LASTPIN (-3450 4825) BN 4
J 0
(-3462 4833);
DISPLAY 0.489362 (-3462 4833);
PAINT GREEN (-3462 4833);
FORCEPROP 2 LAST CDS_LIB mstr_standard
J 0
(-3400 4825);
DISPLAY 0.723404 (-3400 4825);
PAINT MONO (-3400 4825);
DISPLAY INVISIBLE (-3400 4825);
FORCEPROP 1 LAST BODY_TYPE PLUMBING
J 0
(-3400 4875);
DISPLAY 0.872340 (-3400 4875);
PAINT GREEN (-3400 4875);
DISPLAY INVISIBLE (-3400 4875);
FORCEPROP 1 LAST HDL_TAP TRUE
J 0
(-3075 4700);
DISPLAY 0.872340 (-3075 4700);
DISPLAY INVISIBLE (-3075 4700);
FORCEPROP 1 LAST PATH I477
J 0
(-3402 4825);
DISPLAY 0.872340 (-3402 4825);
PAINT GREEN (-3402 4825);
DISPLAY INVISIBLE (-3402 4825);
FORCEADD OFFPAGE..2
(-2800 4325);
FORCEPROP 2 LAST $XR0 10 
J 0
(-2611 4325);
DISPLAY 0.638298 (-2611 4325);
PAINT MONO (-2611 4325);
FORCEPROP 2 LAST PATH I478
J 0
(-2500 4375);
DISPLAY 0.808511 (-2500 4375);
DISPLAY INVISIBLE (-2500 4375);
FORCEPROP 1 LAST COMMENT_BODY TRUE
J 0
(-2845 4230);
DISPLAY 0.872340 (-2845 4230);
PAINT GREEN (-2845 4230);
DISPLAY INVISIBLE (-2845 4230);
FORCEPROP 1 LAST OFFPAGE TRUE
J 0
(-2475 4200);
DISPLAY 0.723404 (-2475 4200);
PAINT GREEN (-2475 4200);
DISPLAY INVISIBLE (-2475 4200);
FORCEPROP 2 LAST CDS_LIB mstr_standard
J 0
(-2800 4325);
DISPLAY 0.723404 (-2800 4325);
PAINT MONO (-2800 4325);
DISPLAY INVISIBLE (-2800 4325);
FORCEADD OFFPAGE..2
(-2800 4375);
FORCEPROP 2 LAST $XR0 10 
J 0
(-2611 4375);
DISPLAY 0.638298 (-2611 4375);
PAINT MONO (-2611 4375);
FORCEPROP 2 LAST PATH I479
J 0
(-2500 4425);
DISPLAY 0.808511 (-2500 4425);
DISPLAY INVISIBLE (-2500 4425);
FORCEPROP 1 LAST COMMENT_BODY TRUE
J 0
(-2845 4280);
DISPLAY 0.872340 (-2845 4280);
PAINT GREEN (-2845 4280);
DISPLAY INVISIBLE (-2845 4280);
FORCEPROP 1 LAST OFFPAGE TRUE
J 0
(-2475 4250);
DISPLAY 0.723404 (-2475 4250);
PAINT GREEN (-2475 4250);
DISPLAY INVISIBLE (-2475 4250);
FORCEPROP 2 LAST CDS_LIB mstr_standard
J 0
(-2800 4375);
DISPLAY 0.723404 (-2800 4375);
PAINT MONO (-2800 4375);
DISPLAY INVISIBLE (-2800 4375);
FORCEADD TAP..1
(-3600 4875);
FORCEPROP 3 LASTPIN (-3650 4875) SIG_NAME M_A_CPU0_SA_DQS_DP<4>
J 0
(-3640 4885);
DISPLAY 0.659574 (-3640 4885);
PAINT MONO (-3640 4885);
DISPLAY INVISIBLE (-3640 4885);
FORCEPROP 1 LASTPIN (-3650 4875) BN 4
J 0
(-3662 4883);
DISPLAY 0.489362 (-3662 4883);
PAINT GREEN (-3662 4883);
FORCEPROP 2 LAST CDS_LIB mstr_standard
J 0
(-3600 4875);
DISPLAY 0.723404 (-3600 4875);
PAINT MONO (-3600 4875);
DISPLAY INVISIBLE (-3600 4875);
FORCEPROP 1 LAST BODY_TYPE PLUMBING
J 0
(-3600 4925);
DISPLAY 0.872340 (-3600 4925);
PAINT GREEN (-3600 4925);
DISPLAY INVISIBLE (-3600 4925);
FORCEPROP 1 LAST HDL_TAP TRUE
J 0
(-3275 4750);
DISPLAY 0.872340 (-3275 4750);
DISPLAY INVISIBLE (-3275 4750);
FORCEPROP 1 LAST PATH I480
J 0
(-3602 4875);
DISPLAY 0.872340 (-3602 4875);
PAINT GREEN (-3602 4875);
DISPLAY INVISIBLE (-3602 4875);
FORCEADD TAP..1
(-3600 4975);
FORCEPROP 3 LASTPIN (-3650 4975) SIG_NAME M_A_CPU0_SA_DQS_DP<5>
J 0
(-3640 4985);
DISPLAY 0.659574 (-3640 4985);
PAINT MONO (-3640 4985);
DISPLAY INVISIBLE (-3640 4985);
FORCEPROP 1 LASTPIN (-3650 4975) BN 5
J 0
(-3662 4983);
DISPLAY 0.489362 (-3662 4983);
PAINT GREEN (-3662 4983);
FORCEPROP 2 LAST CDS_LIB mstr_standard
J 0
(-3600 4975);
DISPLAY 0.723404 (-3600 4975);
PAINT MONO (-3600 4975);
DISPLAY INVISIBLE (-3600 4975);
FORCEPROP 1 LAST BODY_TYPE PLUMBING
J 0
(-3600 5025);
DISPLAY 0.872340 (-3600 5025);
PAINT GREEN (-3600 5025);
DISPLAY INVISIBLE (-3600 5025);
FORCEPROP 1 LAST HDL_TAP TRUE
J 0
(-3275 4850);
DISPLAY 0.872340 (-3275 4850);
DISPLAY INVISIBLE (-3275 4850);
FORCEPROP 1 LAST PATH I481
J 0
(-3602 4975);
DISPLAY 0.872340 (-3602 4975);
PAINT GREEN (-3602 4975);
DISPLAY INVISIBLE (-3602 4975);
FORCEADD TAP..1
(-3600 5075);
FORCEPROP 3 LASTPIN (-3650 5075) SIG_NAME M_A_CPU0_SA_DQS_DP<6>
J 0
(-3640 5085);
DISPLAY 0.659574 (-3640 5085);
PAINT MONO (-3640 5085);
DISPLAY INVISIBLE (-3640 5085);
FORCEPROP 1 LASTPIN (-3650 5075) BN 6
J 0
(-3662 5083);
DISPLAY 0.489362 (-3662 5083);
PAINT GREEN (-3662 5083);
FORCEPROP 2 LAST CDS_LIB mstr_standard
J 0
(-3600 5075);
DISPLAY 0.723404 (-3600 5075);
PAINT MONO (-3600 5075);
DISPLAY INVISIBLE (-3600 5075);
FORCEPROP 1 LAST BODY_TYPE PLUMBING
J 0
(-3600 5125);
DISPLAY 0.872340 (-3600 5125);
PAINT GREEN (-3600 5125);
DISPLAY INVISIBLE (-3600 5125);
FORCEPROP 1 LAST HDL_TAP TRUE
J 0
(-3275 4950);
DISPLAY 0.872340 (-3275 4950);
DISPLAY INVISIBLE (-3275 4950);
FORCEPROP 1 LAST PATH I482
J 0
(-3602 5075);
DISPLAY 0.872340 (-3602 5075);
PAINT GREEN (-3602 5075);
DISPLAY INVISIBLE (-3602 5075);
FORCEADD TAP..1
(-3400 5125);
FORCEPROP 3 LASTPIN (-3450 5125) SIG_NAME M_A_CPU0_SA_DQS_DN<7>
J 0
(-3440 5135);
DISPLAY 0.659574 (-3440 5135);
PAINT MONO (-3440 5135);
DISPLAY INVISIBLE (-3440 5135);
FORCEPROP 1 LASTPIN (-3450 5125) BN 7
J 0
(-3462 5133);
DISPLAY 0.489362 (-3462 5133);
PAINT GREEN (-3462 5133);
FORCEPROP 2 LAST CDS_LIB mstr_standard
J 0
(-3400 5125);
DISPLAY 0.723404 (-3400 5125);
PAINT MONO (-3400 5125);
DISPLAY INVISIBLE (-3400 5125);
FORCEPROP 1 LAST BODY_TYPE PLUMBING
J 0
(-3400 5175);
DISPLAY 0.872340 (-3400 5175);
PAINT GREEN (-3400 5175);
DISPLAY INVISIBLE (-3400 5175);
FORCEPROP 1 LAST HDL_TAP TRUE
J 0
(-3075 5000);
DISPLAY 0.872340 (-3075 5000);
DISPLAY INVISIBLE (-3075 5000);
FORCEPROP 1 LAST PATH I483
J 0
(-3402 5125);
DISPLAY 0.872340 (-3402 5125);
PAINT GREEN (-3402 5125);
DISPLAY INVISIBLE (-3402 5125);
FORCEADD TAP..1
(-3400 5025);
FORCEPROP 3 LASTPIN (-3450 5025) SIG_NAME M_A_CPU0_SA_DQS_DN<6>
J 0
(-3440 5035);
DISPLAY 0.659574 (-3440 5035);
PAINT MONO (-3440 5035);
DISPLAY INVISIBLE (-3440 5035);
FORCEPROP 1 LASTPIN (-3450 5025) BN 6
J 0
(-3462 5033);
DISPLAY 0.489362 (-3462 5033);
PAINT GREEN (-3462 5033);
FORCEPROP 2 LAST CDS_LIB mstr_standard
J 0
(-3400 5025);
DISPLAY 0.723404 (-3400 5025);
PAINT MONO (-3400 5025);
DISPLAY INVISIBLE (-3400 5025);
FORCEPROP 1 LAST BODY_TYPE PLUMBING
J 0
(-3400 5075);
DISPLAY 0.872340 (-3400 5075);
PAINT GREEN (-3400 5075);
DISPLAY INVISIBLE (-3400 5075);
FORCEPROP 1 LAST HDL_TAP TRUE
J 0
(-3075 4900);
DISPLAY 0.872340 (-3075 4900);
DISPLAY INVISIBLE (-3075 4900);
FORCEPROP 1 LAST PATH I484
J 0
(-3402 5025);
DISPLAY 0.872340 (-3402 5025);
PAINT GREEN (-3402 5025);
DISPLAY INVISIBLE (-3402 5025);
FORCEADD TAP..1
(-3400 4925);
FORCEPROP 3 LASTPIN (-3450 4925) SIG_NAME M_A_CPU0_SA_DQS_DN<5>
J 0
(-3440 4935);
DISPLAY 0.659574 (-3440 4935);
PAINT MONO (-3440 4935);
DISPLAY INVISIBLE (-3440 4935);
FORCEPROP 1 LASTPIN (-3450 4925) BN 5
J 0
(-3462 4933);
DISPLAY 0.489362 (-3462 4933);
PAINT GREEN (-3462 4933);
FORCEPROP 2 LAST CDS_LIB mstr_standard
J 0
(-3400 4925);
DISPLAY 0.723404 (-3400 4925);
PAINT MONO (-3400 4925);
DISPLAY INVISIBLE (-3400 4925);
FORCEPROP 1 LAST BODY_TYPE PLUMBING
J 0
(-3400 4975);
DISPLAY 0.872340 (-3400 4975);
PAINT GREEN (-3400 4975);
DISPLAY INVISIBLE (-3400 4975);
FORCEPROP 1 LAST HDL_TAP TRUE
J 0
(-3075 4800);
DISPLAY 0.872340 (-3075 4800);
DISPLAY INVISIBLE (-3075 4800);
FORCEPROP 1 LAST PATH I485
J 0
(-3402 4925);
DISPLAY 0.872340 (-3402 4925);
PAINT GREEN (-3402 4925);
DISPLAY INVISIBLE (-3402 4925);
FORCEADD TAP..1
(-3600 5175);
FORCEPROP 3 LASTPIN (-3650 5175) SIG_NAME M_A_CPU0_SA_DQS_DP<7>
J 0
(-3640 5185);
DISPLAY 0.659574 (-3640 5185);
PAINT MONO (-3640 5185);
DISPLAY INVISIBLE (-3640 5185);
FORCEPROP 1 LASTPIN (-3650 5175) BN 7
J 0
(-3662 5183);
DISPLAY 0.489362 (-3662 5183);
PAINT GREEN (-3662 5183);
FORCEPROP 2 LAST CDS_LIB mstr_standard
J 0
(-3600 5175);
DISPLAY 0.723404 (-3600 5175);
PAINT MONO (-3600 5175);
DISPLAY INVISIBLE (-3600 5175);
FORCEPROP 1 LAST BODY_TYPE PLUMBING
J 0
(-3600 5225);
DISPLAY 0.872340 (-3600 5225);
PAINT GREEN (-3600 5225);
DISPLAY INVISIBLE (-3600 5225);
FORCEPROP 1 LAST HDL_TAP TRUE
J 0
(-3275 5050);
DISPLAY 0.872340 (-3275 5050);
DISPLAY INVISIBLE (-3275 5050);
FORCEPROP 1 LAST PATH I486
J 0
(-3602 5175);
DISPLAY 0.872340 (-3602 5175);
PAINT GREEN (-3602 5175);
DISPLAY INVISIBLE (-3602 5175);
FORCEADD TAP..1
(-3600 5275);
FORCEPROP 3 LASTPIN (-3650 5275) SIG_NAME M_A_CPU0_SA_DQS_DP<8>
J 0
(-3640 5285);
DISPLAY 0.659574 (-3640 5285);
PAINT MONO (-3640 5285);
DISPLAY INVISIBLE (-3640 5285);
FORCEPROP 1 LASTPIN (-3650 5275) BN 8
J 0
(-3662 5283);
DISPLAY 0.489362 (-3662 5283);
PAINT GREEN (-3662 5283);
FORCEPROP 2 LAST CDS_LIB mstr_standard
J 0
(-3600 5275);
DISPLAY 0.723404 (-3600 5275);
PAINT MONO (-3600 5275);
DISPLAY INVISIBLE (-3600 5275);
FORCEPROP 1 LAST BODY_TYPE PLUMBING
J 0
(-3600 5325);
DISPLAY 0.872340 (-3600 5325);
PAINT GREEN (-3600 5325);
DISPLAY INVISIBLE (-3600 5325);
FORCEPROP 1 LAST HDL_TAP TRUE
J 0
(-3275 5150);
DISPLAY 0.872340 (-3275 5150);
DISPLAY INVISIBLE (-3275 5150);
FORCEPROP 1 LAST PATH I487
J 0
(-3602 5275);
DISPLAY 0.872340 (-3602 5275);
PAINT GREEN (-3602 5275);
DISPLAY INVISIBLE (-3602 5275);
FORCEADD TAP..1
(-3600 5375);
FORCEPROP 3 LASTPIN (-3650 5375) SIG_NAME M_A_CPU0_SA_DQS_DP<9>
J 0
(-3640 5385);
DISPLAY 0.659574 (-3640 5385);
PAINT MONO (-3640 5385);
DISPLAY INVISIBLE (-3640 5385);
FORCEPROP 1 LASTPIN (-3650 5375) BN 9
J 0
(-3662 5383);
DISPLAY 0.489362 (-3662 5383);
PAINT GREEN (-3662 5383);
FORCEPROP 2 LAST CDS_LIB mstr_standard
J 0
(-3600 5375);
DISPLAY 0.723404 (-3600 5375);
PAINT MONO (-3600 5375);
DISPLAY INVISIBLE (-3600 5375);
FORCEPROP 1 LAST BODY_TYPE PLUMBING
J 0
(-3600 5425);
DISPLAY 0.872340 (-3600 5425);
PAINT GREEN (-3600 5425);
DISPLAY INVISIBLE (-3600 5425);
FORCEPROP 1 LAST HDL_TAP TRUE
J 0
(-3275 5250);
DISPLAY 0.872340 (-3275 5250);
DISPLAY INVISIBLE (-3275 5250);
FORCEPROP 1 LAST PATH I488
J 0
(-3602 5375);
DISPLAY 0.872340 (-3602 5375);
PAINT GREEN (-3602 5375);
DISPLAY INVISIBLE (-3602 5375);
FORCEADD TAP..1
(-3400 5325);
FORCEPROP 3 LASTPIN (-3450 5325) SIG_NAME M_A_CPU0_SA_DQS_DN<9>
J 0
(-3440 5335);
DISPLAY 0.659574 (-3440 5335);
PAINT MONO (-3440 5335);
DISPLAY INVISIBLE (-3440 5335);
FORCEPROP 1 LASTPIN (-3450 5325) BN 9
J 0
(-3462 5333);
DISPLAY 0.489362 (-3462 5333);
PAINT GREEN (-3462 5333);
FORCEPROP 2 LAST CDS_LIB mstr_standard
J 0
(-3400 5325);
DISPLAY 0.723404 (-3400 5325);
PAINT MONO (-3400 5325);
DISPLAY INVISIBLE (-3400 5325);
FORCEPROP 1 LAST BODY_TYPE PLUMBING
J 0
(-3400 5375);
DISPLAY 0.872340 (-3400 5375);
PAINT GREEN (-3400 5375);
DISPLAY INVISIBLE (-3400 5375);
FORCEPROP 1 LAST HDL_TAP TRUE
J 0
(-3075 5200);
DISPLAY 0.872340 (-3075 5200);
DISPLAY INVISIBLE (-3075 5200);
FORCEPROP 1 LAST PATH I489
J 0
(-3402 5325);
DISPLAY 0.872340 (-3402 5325);
PAINT GREEN (-3402 5325);
DISPLAY INVISIBLE (-3402 5325);
FORCEADD TAP..1
(-3400 5225);
FORCEPROP 3 LASTPIN (-3450 5225) SIG_NAME M_A_CPU0_SA_DQS_DN<8>
J 0
(-3440 5235);
DISPLAY 0.659574 (-3440 5235);
PAINT MONO (-3440 5235);
DISPLAY INVISIBLE (-3440 5235);
FORCEPROP 1 LASTPIN (-3450 5225) BN 8
J 0
(-3462 5233);
DISPLAY 0.489362 (-3462 5233);
PAINT GREEN (-3462 5233);
FORCEPROP 2 LAST CDS_LIB mstr_standard
J 0
(-3400 5225);
DISPLAY 0.723404 (-3400 5225);
PAINT MONO (-3400 5225);
DISPLAY INVISIBLE (-3400 5225);
FORCEPROP 1 LAST BODY_TYPE PLUMBING
J 0
(-3400 5275);
DISPLAY 0.872340 (-3400 5275);
PAINT GREEN (-3400 5275);
DISPLAY INVISIBLE (-3400 5275);
FORCEPROP 1 LAST HDL_TAP TRUE
J 0
(-3075 5100);
DISPLAY 0.872340 (-3075 5100);
DISPLAY INVISIBLE (-3075 5100);
FORCEPROP 1 LAST PATH I490
J 0
(-3402 5225);
DISPLAY 0.872340 (-3402 5225);
PAINT GREEN (-3402 5225);
DISPLAY INVISIBLE (-3402 5225);
FORCEADD OFFPAGE..2
(-2800 5375);
FORCEPROP 2 LAST $XR0 10 
J 0
(-2611 5375);
DISPLAY 0.638298 (-2611 5375);
PAINT MONO (-2611 5375);
FORCEPROP 2 LAST PATH I491
J 0
(-2500 5425);
DISPLAY 0.808511 (-2500 5425);
DISPLAY INVISIBLE (-2500 5425);
FORCEPROP 1 LAST COMMENT_BODY TRUE
J 0
(-2845 5280);
DISPLAY 0.872340 (-2845 5280);
PAINT GREEN (-2845 5280);
DISPLAY INVISIBLE (-2845 5280);
FORCEPROP 1 LAST OFFPAGE TRUE
J 0
(-2475 5250);
DISPLAY 0.723404 (-2475 5250);
PAINT GREEN (-2475 5250);
DISPLAY INVISIBLE (-2475 5250);
FORCEPROP 2 LAST CDS_LIB mstr_standard
J 0
(-2800 5375);
DISPLAY 0.723404 (-2800 5375);
PAINT MONO (-2800 5375);
DISPLAY INVISIBLE (-2800 5375);
FORCEADD OFFPAGE..2
(-2800 5425);
FORCEPROP 2 LAST $XR0 10 
J 0
(-2611 5425);
DISPLAY 0.638298 (-2611 5425);
PAINT MONO (-2611 5425);
FORCEPROP 2 LAST PATH I492
J 0
(-2500 5475);
DISPLAY 0.808511 (-2500 5475);
DISPLAY INVISIBLE (-2500 5475);
FORCEPROP 1 LAST COMMENT_BODY TRUE
J 0
(-2845 5330);
DISPLAY 0.872340 (-2845 5330);
PAINT GREEN (-2845 5330);
DISPLAY INVISIBLE (-2845 5330);
FORCEPROP 1 LAST OFFPAGE TRUE
J 0
(-2475 5300);
DISPLAY 0.723404 (-2475 5300);
PAINT GREEN (-2475 5300);
DISPLAY INVISIBLE (-2475 5300);
FORCEPROP 2 LAST CDS_LIB mstr_standard
J 0
(-2800 5425);
DISPLAY 0.723404 (-2800 5425);
PAINT MONO (-2800 5425);
DISPLAY INVISIBLE (-2800 5425);
FORCEADD VCC_CORE..1
(-8875 3525);
FORCEPROP 3 LASTPIN (-8875 3475) SIG_NAME P3V3_STBY\g
J 0
(-8865 3485);
DISPLAY 0.659574 (-8865 3485);
PAINT MONO (-8865 3485);
DISPLAY INVISIBLE (-8865 3485);
FORCEPROP 1 LAST HDL_POWER P3V3_STBY
J 1
(-8875 3575);
DISPLAY 0.489362 (-8875 3575);
PAINT GREEN (-8875 3575);
FORCEPROP 2 LAST CDS_LIB mstr_symbols
J 0
(-8875 3525);
PAINT MONO (-8875 3525);
DISPLAY INVISIBLE (-8875 3525);
FORCEPROP 1 LAST PATH I493
J 0
(-8825 3550);
DISPLAY 0.872340 (-8825 3550);
PAINT GREEN (-8825 3550);
DISPLAY INVISIBLE (-8825 3550);
FORCEPROP 0 LAST VOLTAGE 3.3
J 0
(-9150 3675);
DISPLAY 1.021277 (-9150 3675);
PAINT SKYBLUE (-9150 3675);
DISPLAY INVISIBLE (-9150 3675);
FORCEPROP 2 LAST ROOM PVCCINFAON_CPU0_CTRL
J 0
(-8875 3625);
DISPLAY 0.808511 (-8875 3625);
PAINT RED (-8875 3625);
DISPLAY INVISIBLE (-8875 3625);
FORCEADD OFFPAGE..6
(-8350 2875);
FORCEPROP 2 LAST $XR5 136 
J 0
(-9109 2875);
DISPLAY 0.638298 (-9109 2875);
PAINT MONO (-9109 2875);
FORCEPROP 2 LAST $XR4 90 
J 0
(-8989 2875);
DISPLAY 0.638298 (-8989 2875);
PAINT MONO (-8989 2875);
FORCEPROP 2 LAST $XR3 89 
J 0
(-8899 2875);
DISPLAY 0.638298 (-8899 2875);
PAINT MONO (-8899 2875);
FORCEPROP 2 LAST $XR2 88 
J 0
(-8809 2875);
DISPLAY 0.638298 (-8809 2875);
PAINT MONO (-8809 2875);
FORCEPROP 2 LAST $XR1 87 
J 0
(-8719 2875);
DISPLAY 0.638298 (-8719 2875);
PAINT MONO (-8719 2875);
FORCEPROP 2 LAST $XR0 86 
J 0
(-8629 2875);
DISPLAY 0.638298 (-8629 2875);
PAINT MONO (-8629 2875);
FORCEPROP 2 LAST PATH I494
J 0
(-8625 3025);
DISPLAY 0.808511 (-8625 3025);
DISPLAY INVISIBLE (-8625 3025);
FORCEPROP 1 LAST COMMENT_BODY TRUE
J 0
(-8250 2800);
DISPLAY 0.872340 (-8250 2800);
PAINT GREEN (-8250 2800);
DISPLAY INVISIBLE (-8250 2800);
FORCEPROP 1 LAST OFFPAGE TRUE
J 0
(-8025 2750);
DISPLAY 0.872340 (-8025 2750);
PAINT GREEN (-8025 2750);
DISPLAY INVISIBLE (-8025 2750);
FORCEPROP 2 LAST CDS_LIB mstr_standard
J 0
(-8350 2875);
DISPLAY 0.808511 (-8350 2875);
DISPLAY INVISIBLE (-8350 2875);
FORCEADD OFFPAGE..1
(-8350 2925);
FORCEPROP 2 LAST $XR0 85 
J 0
(-8601 2925);
DISPLAY 0.638298 (-8601 2925);
PAINT MONO (-8601 2925);
FORCEPROP 2 LAST PATH I495
J 0
(-8300 3000);
DISPLAY 0.808511 (-8300 3000);
DISPLAY INVISIBLE (-8300 3000);
FORCEPROP 1 LAST COMMENT_BODY TRUE
J 0
(-8225 2825);
DISPLAY 0.872340 (-8225 2825);
PAINT GREEN (-8225 2825);
DISPLAY INVISIBLE (-8225 2825);
FORCEPROP 1 LAST OFFPAGE TRUE
J 0
(-8025 2800);
DISPLAY 0.872340 (-8025 2800);
PAINT GREEN (-8025 2800);
DISPLAY INVISIBLE (-8025 2800);
FORCEPROP 2 LAST CDS_LIB mstr_standard
J 0
(-8350 2925);
DISPLAY 0.808511 (-8350 2925);
DISPLAY INVISIBLE (-8350 2925);
FORCEADD OFFPAGE..1
(-8375 2725);
FORCEPROP 2 LASTPIN (-8325 2725) SIG_NAME I3C_SPD_DDRAF_CPU0_SCL
J 0
(-8335 2735);
DISPLAY 0.446809 (-8335 2735);
FORCEPROP 2 LAST $XR5 90 
J 0
(-9107 2725);
DISPLAY 0.638298 (-9107 2725);
PAINT MONO (-9107 2725);
FORCEPROP 2 LAST $XR4 89 
J 0
(-9017 2725);
DISPLAY 0.638298 (-9017 2725);
PAINT MONO (-9017 2725);
FORCEPROP 2 LAST $XR3 88 
J 0
(-8927 2725);
DISPLAY 0.638298 (-8927 2725);
PAINT MONO (-8927 2725);
FORCEPROP 2 LAST $XR2 87 
J 0
(-8837 2725);
DISPLAY 0.638298 (-8837 2725);
PAINT MONO (-8837 2725);
FORCEPROP 2 LAST $XR1 86 
J 0
(-8747 2725);
DISPLAY 0.638298 (-8747 2725);
PAINT MONO (-8747 2725);
FORCEPROP 2 LAST $XR0 136 
J 0
(-8657 2725);
DISPLAY 0.638298 (-8657 2725);
PAINT MONO (-8657 2725);
FORCEPROP 2 LAST PATH I496
J 0
(-8800 2775);
DISPLAY 0.808511 (-8800 2775);
DISPLAY INVISIBLE (-8800 2775);
FORCEPROP 1 LAST COMMENT_BODY TRUE
J 0
(-8250 2625);
DISPLAY 0.872340 (-8250 2625);
PAINT GREEN (-8250 2625);
DISPLAY INVISIBLE (-8250 2625);
FORCEPROP 1 LAST OFFPAGE TRUE
J 0
(-8050 2600);
DISPLAY 0.872340 (-8050 2600);
PAINT GREEN (-8050 2600);
DISPLAY INVISIBLE (-8050 2600);
FORCEPROP 2 LAST CDS_LIB mstr_standard
J 0
(-8375 2725);
DISPLAY 0.808511 (-8375 2725);
DISPLAY INVISIBLE (-8375 2725);
FORCEADD OFFPAGE..5
(-7275 1500);
FORCEPROP 2 LAST $XR0 85 
J 0
(-7529 1500);
DISPLAY 0.638298 (-7529 1500);
PAINT MONO (-7529 1500);
FORCEPROP 2 LAST PATH I497
J 0
(-7225 1575);
DISPLAY 0.808511 (-7225 1575);
DISPLAY INVISIBLE (-7225 1575);
FORCEPROP 1 LAST COMMENT_BODY TRUE
J 0
(-7175 1425);
DISPLAY 0.872340 (-7175 1425);
PAINT GREEN (-7175 1425);
DISPLAY INVISIBLE (-7175 1425);
FORCEPROP 1 LAST OFFPAGE TRUE
J 0
(-6950 1375);
DISPLAY 0.872340 (-6950 1375);
PAINT GREEN (-6950 1375);
DISPLAY INVISIBLE (-6950 1375);
FORCEPROP 2 LAST BOM_COST MEM
J 0
(-7350 1575);
DISPLAY 0.808511 (-7350 1575);
DISPLAY INVISIBLE (-7350 1575);
FORCEPROP 2 LAST CDS_LIB mstr_standard
J 0
(-7275 1500);
DISPLAY 0.808511 (-7275 1500);
DISPLAY INVISIBLE (-7275 1500);
FORCEADD GND..1
(-6500 1100);
FORCEPROP 3 LASTPIN (-6500 1150) SIG_NAME GND\g
J 0
(-6490 1160);
DISPLAY 0.659574 (-6490 1160);
PAINT MONO (-6490 1160);
DISPLAY INVISIBLE (-6490 1160);
FORCEPROP 2 LAST BOM_COST MEM
J 0
(-6600 1175);
DISPLAY 0.808511 (-6600 1175);
DISPLAY INVISIBLE (-6600 1175);
FORCEPROP 2 LAST CDS_LIB mstr_symbols
J 0
(-6500 1100);
DISPLAY 0.808511 (-6500 1100);
DISPLAY INVISIBLE (-6500 1100);
FORCEPROP 1 LAST SIZE 1B
J 0
(-6425 1050);
DISPLAY 0.851064 (-6425 1050);
PAINT GREEN (-6425 1050);
DISPLAY INVISIBLE (-6425 1050);
FORCEPROP 1 LAST BODY_TYPE PLUMBING
J 0
(-6545 1057);
DISPLAY 0.340426 (-6545 1057);
PAINT GREEN (-6545 1057);
DISPLAY INVISIBLE (-6545 1057);
FORCEPROP 1 LAST PATH I498
J 0
(-6425 1100);
DISPLAY 0.872340 (-6425 1100);
PAINT GREEN (-6425 1100);
DISPLAY INVISIBLE (-6425 1100);
FORCEPROP 1 LAST VOLTAGE 0.0
J 0
(-6545 1057);
DISPLAY 0.723404 (-6545 1057);
PAINT SKYBLUE (-6545 1057);
DISPLAY INVISIBLE (-6545 1057);
FORCEPROP 1 LAST HDL_POWER GND
J 0
(-6500 1250);
DISPLAY 0.851064 (-6500 1250);
PAINT GREEN (-6500 1250);
DISPLAY INVISIBLE (-6500 1250);
FORCEADD Q_RES..2
(-6500 1325);
FORCEPROP 1 LAST LOCATION R7
J 0
(-6455 1450);
DISPLAY 0.489362 (-6455 1450);
PAINT SKYBLUE (-6455 1450);
FORCEPROP 2 LAST SEC 1
J 0
(-6450 1550);
DISPLAY 0.808511 (-6450 1550);
PAINT MONO (-6450 1550);
DISPLAY INVISIBLE (-6450 1550);
FORCEPROP 1 LASTPIN (-6500 1425) $PN 1
J 0
(-6495 1387);
DISPLAY 0.489362 (-6495 1387);
PAINT WHITE (-6495 1387);
FORCEPROP 1 LASTPIN (-6500 1225) $PN 2
J 0
(-6495 1235);
DISPLAY 0.489362 (-6495 1235);
PAINT WHITE (-6495 1235);
FORCEPROP 0 LASTPIN (-6500 1425) XNET_PINS 3
R 1
J 0
(-6510 1435);
DISPLAY 0.808511 (-6510 1435);
PAINT MONO (-6510 1435);
DISPLAY INVISIBLE (-6510 1435);
FORCEPROP 0 LASTPIN (-6500 1225) XNET_PINS 2
R 1
J 2
(-6510 1215);
DISPLAY 0.808511 (-6510 1215);
PAINT MONO (-6510 1215);
DISPLAY INVISIBLE (-6510 1215);
FORCEPROP 1 LAST WATTAGE 1/16W
J 0
(-6460 1300);
DISPLAY 0.489362 (-6460 1300);
PAINT SKYBLUE (-6460 1300);
FORCEPROP 1 LAST MATERIAL CHIP
J 0
(-6460 1250);
DISPLAY 0.489362 (-6460 1250);
PAINT SKYBLUE (-6460 1250);
FORCEPROP 1 LAST TOLERANCE 1%
J 0
(-6455 1350);
DISPLAY 0.489362 (-6455 1350);
PAINT SKYBLUE (-6455 1350);
FORCEPROP 1 LAST VALUE 10K
J 0
(-6455 1400);
DISPLAY 0.489362 (-6455 1400);
PAINT SKYBLUE (-6455 1400);
FORCEPROP 1 LAST PART_NUMBER CS31002FB08
J 0
(-6460 1200);
DISPLAY 0.489362 (-6460 1200);
PAINT SKYBLUE (-6460 1200);
FORCEPROP 1 LAST PACK_TYPE 0402LF
J 0
(-6460 1150);
DISPLAY 0.489362 (-6460 1150);
PAINT SKYBLUE (-6460 1150);
FORCEPROP 2 LAST CDS_LIB pure_quanta
J 0
(-6500 1325);
DISPLAY INVISIBLE (-6500 1325);
FORCEPROP 2 LAST SEC_TYPE 0402LF
J 0
(-6450 1550);
DISPLAY 0.808511 (-6450 1550);
PAINT MONO (-6450 1550);
DISPLAY INVISIBLE (-6450 1550);
FORCEPROP 2 LAST BOM_COST MEM
J 0
(-6450 1500);
DISPLAY 0.808511 (-6450 1500);
DISPLAY INVISIBLE (-6450 1500);
FORCEPROP 1 LAST PATH I499
J 0
(-6450 1500);
DISPLAY 0.978723 (-6450 1500);
PAINT WHITE (-6450 1500);
DISPLAY INVISIBLE (-6450 1500);
FORCEPROP 2 LAST ROOM MEM_CH_A_CPU0_DIMM1
J 0
(-6450 1550);
DISPLAY 0.808511 (-6450 1550);
PAINT RED (-6450 1550);
DISPLAY INVISIBLE (-6450 1550);
FORCEADD OFFPAGE..6
(-9075 2250);
FORCEPROP 2 LAST $XR5 81 
J 0
(-9414 2286);
DISPLAY 0.638298 (-9414 2286);
PAINT MONO (-9414 2286);
FORCEPROP 2 LAST $XR4 90 
J 0
(-9324 2286);
DISPLAY 0.638298 (-9324 2286);
PAINT MONO (-9324 2286);
FORCEPROP 2 LAST $XR3 89 
J 0
(-9414 2214);
DISPLAY 0.638298 (-9414 2214);
PAINT MONO (-9414 2214);
FORCEPROP 2 LAST $XR2 88 
J 0
(-9324 2214);
DISPLAY 0.638298 (-9324 2214);
PAINT MONO (-9324 2214);
FORCEPROP 2 LAST $XR1 87 
J 0
(-9414 2250);
DISPLAY 0.638298 (-9414 2250);
PAINT MONO (-9414 2250);
FORCEPROP 2 LAST $XR0 86 
J 0
(-9324 2250);
DISPLAY 0.638298 (-9324 2250);
PAINT MONO (-9324 2250);
FORCEPROP 2 LAST PATH I509
J 0
(-9025 2325);
DISPLAY 0.808511 (-9025 2325);
DISPLAY INVISIBLE (-9025 2325);
FORCEPROP 1 LAST COMMENT_BODY TRUE
J 0
(-8975 2175);
DISPLAY 0.872340 (-8975 2175);
PAINT GREEN (-8975 2175);
DISPLAY INVISIBLE (-8975 2175);
FORCEPROP 1 LAST OFFPAGE TRUE
J 0
(-8750 2125);
DISPLAY 0.872340 (-8750 2125);
PAINT GREEN (-8750 2125);
DISPLAY INVISIBLE (-8750 2125);
FORCEPROP 2 LAST CDS_LIB mstr_standard
J 0
(-9075 2250);
DISPLAY 0.808511 (-9075 2250);
DISPLAY INVISIBLE (-9075 2250);
FORCEADD OFFPAGE..5
(-8350 3075);
FORCEPROP 2 LAST $XR0 10 
J 0
(-8574 3075);
DISPLAY 0.638298 (-8574 3075);
PAINT MONO (-8574 3075);
FORCEPROP 2 LAST PATH I518
J 0
(-8300 3150);
DISPLAY 1.021277 (-8300 3150);
DISPLAY INVISIBLE (-8300 3150);
FORCEPROP 1 LAST COMMENT_BODY TRUE
J 0
(-8250 3000);
DISPLAY 0.872340 (-8250 3000);
PAINT GREEN (-8250 3000);
DISPLAY INVISIBLE (-8250 3000);
FORCEPROP 1 LAST OFFPAGE TRUE
J 0
(-8025 2950);
DISPLAY 0.872340 (-8025 2950);
PAINT GREEN (-8025 2950);
DISPLAY INVISIBLE (-8025 2950);
FORCEPROP 2 LAST CDS_LIB mstr_standard
J 0
(-8350 3075);
DISPLAY INVISIBLE (-8350 3075);
FORCEADD Q_CAP..1
R 2
(-2950 6050);
FORCEPROP 1 LAST LOCATION C89
J 2
(-3000 6150);
DISPLAY 0.489362 (-3000 6150);
PAINT SKYBLUE (-3000 6150);
FORCEPROP 0 LAST $SEC 1
J 0
(-3000 6200);
DISPLAY 0.680851 (-3000 6200);
PAINT MONO (-3000 6200);
DISPLAY INVISIBLE (-3000 6200);
FORCEPROP 0 LAST CDS_SEC 1
J 0
(-3000 6200);
DISPLAY 1.021277 (-3000 6200);
DISPLAY INVISIBLE (-3000 6200);
FORCEPROP 1 LASTPIN (-2950 6150) $PN 1
J 2
(-2960 6130);
DISPLAY 0.489362 (-2960 6130);
PAINT MONO (-2960 6130);
FORCEPROP 1 LASTPIN (-2950 5950) $PN 2
J 2
(-2960 5930);
DISPLAY 0.489362 (-2960 5930);
PAINT MONO (-2960 5930);
FORCEPROP 1 LAST MATERIAL X6S
J 2
(-3000 5950);
DISPLAY 0.489362 (-3000 5950);
PAINT SKYBLUE (-3000 5950);
FORCEPROP 1 LAST TOLERANCE 10%
J 2
(-3000 6000);
DISPLAY 0.489362 (-3000 6000);
PAINT SKYBLUE (-3000 6000);
FORCEPROP 1 LAST VALUE 10UF
J 2
(-3000 6100);
DISPLAY 0.489362 (-3000 6100);
PAINT SKYBLUE (-3000 6100);
FORCEPROP 1 LAST VOLTAGE 25V
J 2
(-3000 6050);
DISPLAY 0.489362 (-3000 6050);
PAINT SKYBLUE (-3000 6050);
FORCEPROP 1 LAST PACK_TYPE C0805
J 2
(-3000 5850);
DISPLAY 0.489362 (-3000 5850);
PAINT SKYBLUE (-3000 5850);
FORCEPROP 1 LAST PART_NUMBER CH6104KEA00
J 2
(-3000 5900);
DISPLAY 0.489362 (-3000 5900);
PAINT SKYBLUE (-3000 5900);
FORCEPROP 2 LAST CDS_LIB pure_quanta
J 0
(-2950 6050);
DISPLAY INVISIBLE (-2950 6050);
FORCEPROP 0 LAST BOM_COST MEM
J 2
(-3005 6195);
DISPLAY 0.595745 (-3005 6195);
PAINT MONO (-3005 6195);
DISPLAY INVISIBLE (-3005 6195);
FORCEPROP 1 LAST PATH I519
J 2
(-3000 6200);
DISPLAY 0.978723 (-3000 6200);
PAINT WHITE (-3000 6200);
DISPLAY INVISIBLE (-3000 6200);
FORCEPROP 0 LAST ROOM MEM_CH_A_CPU0_DIMM1
J 2
(-3005 6195);
DISPLAY 0.595745 (-3005 6195);
PAINT RED (-3005 6195);
DISPLAY INVISIBLE (-3005 6195);
FORCEADD GND..1
(-2950 5700);
FORCEPROP 3 LASTPIN (-2950 5750) SIG_NAME GND\g
J 0
(-2940 5760);
DISPLAY 0.659574 (-2940 5760);
PAINT MONO (-2940 5760);
DISPLAY INVISIBLE (-2940 5760);
FORCEPROP 2 LAST BOM_COST MEM
J 0
(-2925 5825);
DISPLAY 0.659574 (-2925 5825);
DISPLAY INVISIBLE (-2925 5825);
FORCEPROP 1 LAST SIZE 1B
J 0
(-2875 5650);
DISPLAY 0.723404 (-2875 5650);
PAINT GREEN (-2875 5650);
DISPLAY INVISIBLE (-2875 5650);
FORCEPROP 2 LAST CDS_LIB mstr_symbols
J 0
(-2950 5700);
DISPLAY 0.808511 (-2950 5700);
DISPLAY INVISIBLE (-2950 5700);
FORCEPROP 1 LAST BODY_TYPE PLUMBING
J 0
(-2995 5657);
DISPLAY 0.276596 (-2995 5657);
PAINT GREEN (-2995 5657);
DISPLAY INVISIBLE (-2995 5657);
FORCEPROP 1 LAST PATH I522
J 0
(-2875 5700);
DISPLAY 0.872340 (-2875 5700);
PAINT AQUA (-2875 5700);
DISPLAY INVISIBLE (-2875 5700);
FORCEPROP 1 LAST VOLTAGE 0
J 0
(-2970 5795);
DISPLAY 0.829787 (-2970 5795);
PAINT SKYBLUE (-2970 5795);
DISPLAY INVISIBLE (-2970 5795);
FORCEPROP 2 LAST ROOM MEM_EFGH_DECOUPLING_CAPS
J 0
(-2925 5775);
DISPLAY 0.659574 (-2925 5775);
PAINT RED (-2925 5775);
DISPLAY INVISIBLE (-2925 5775);
FORCEPROP 1 LAST HDL_POWER GND
J 0
(-2950 5850);
DISPLAY 0.723404 (-2950 5850);
PAINT GREEN (-2950 5850);
DISPLAY INVISIBLE (-2950 5850);
FORCEADD Q_CAP..1
R 2
(-9000 3225);
FORCEPROP 1 LAST LOCATION C88
J 2
(-9050 3325);
DISPLAY 0.489362 (-9050 3325);
PAINT SKYBLUE (-9050 3325);
FORCEPROP 0 LAST $SEC 1
J 0
(-9050 3375);
DISPLAY 0.680851 (-9050 3375);
PAINT MONO (-9050 3375);
DISPLAY INVISIBLE (-9050 3375);
FORCEPROP 0 LAST CDS_SEC 1
J 0
(-9050 3375);
DISPLAY 1.021277 (-9050 3375);
DISPLAY INVISIBLE (-9050 3375);
FORCEPROP 1 LASTPIN (-9000 3325) $PN 1
J 2
(-9010 3305);
DISPLAY 0.489362 (-9010 3305);
PAINT MONO (-9010 3305);
FORCEPROP 1 LASTPIN (-9000 3125) $PN 2
J 2
(-9010 3105);
DISPLAY 0.489362 (-9010 3105);
PAINT MONO (-9010 3105);
FORCEPROP 1 LAST VOLTAGE 25V
J 2
(-9050 3225);
DISPLAY 0.489362 (-9050 3225);
PAINT SKYBLUE (-9050 3225);
FORCEPROP 1 LAST MATERIAL X7R
J 2
(-9050 3125);
DISPLAY 0.489362 (-9050 3125);
PAINT SKYBLUE (-9050 3125);
FORCEPROP 1 LAST TOLERANCE 10%
J 2
(-9050 3175);
DISPLAY 0.489362 (-9050 3175);
PAINT SKYBLUE (-9050 3175);
FORCEPROP 1 LAST VALUE 0.1UF
J 2
(-9050 3275);
DISPLAY 0.489362 (-9050 3275);
PAINT SKYBLUE (-9050 3275);
FORCEPROP 1 LAST PACK_TYPE 0402
J 2
(-9050 3025);
DISPLAY 0.489362 (-9050 3025);
PAINT SKYBLUE (-9050 3025);
FORCEPROP 1 LAST PART_NUMBER CH4104K1B00
J 2
(-9050 3075);
DISPLAY 0.489362 (-9050 3075);
PAINT SKYBLUE (-9050 3075);
FORCEPROP 0 LAST BOM_COST MEM
J 2
(-9055 3370);
DISPLAY 0.595745 (-9055 3370);
PAINT MONO (-9055 3370);
DISPLAY INVISIBLE (-9055 3370);
FORCEPROP 2 LAST CDS_LIB pure_quanta
J 0
(-9000 3225);
DISPLAY INVISIBLE (-9000 3225);
FORCEPROP 1 LAST PATH I523
J 2
(-9050 3375);
DISPLAY 0.978723 (-9050 3375);
PAINT WHITE (-9050 3375);
DISPLAY INVISIBLE (-9050 3375);
FORCEPROP 0 LAST ROOM MEM_CH_A_CPU0_DIMM1
J 2
(-9055 3370);
DISPLAY 0.595745 (-9055 3370);
PAINT RED (-9055 3370);
DISPLAY INVISIBLE (-9055 3370);
FORCEADD GND..1
(-9000 3000);
FORCEPROP 3 LASTPIN (-9000 3050) SIG_NAME GND\g
J 0
(-8990 3060);
DISPLAY 0.659574 (-8990 3060);
PAINT MONO (-8990 3060);
DISPLAY INVISIBLE (-8990 3060);
FORCEPROP 2 LAST BOM_COST MEM
J 0
(-8975 3125);
DISPLAY 0.659574 (-8975 3125);
DISPLAY INVISIBLE (-8975 3125);
FORCEPROP 1 LAST SIZE 1B
J 0
(-8925 2950);
DISPLAY 0.723404 (-8925 2950);
PAINT GREEN (-8925 2950);
DISPLAY INVISIBLE (-8925 2950);
FORCEPROP 2 LAST CDS_LIB mstr_symbols
J 0
(-9000 3000);
DISPLAY 0.808511 (-9000 3000);
DISPLAY INVISIBLE (-9000 3000);
FORCEPROP 1 LAST BODY_TYPE PLUMBING
J 0
(-9045 2957);
DISPLAY 0.276596 (-9045 2957);
PAINT GREEN (-9045 2957);
DISPLAY INVISIBLE (-9045 2957);
FORCEPROP 1 LAST PATH I524
J 0
(-8925 3000);
DISPLAY 0.872340 (-8925 3000);
PAINT AQUA (-8925 3000);
DISPLAY INVISIBLE (-8925 3000);
FORCEPROP 1 LAST VOLTAGE 0
J 0
(-9020 3095);
DISPLAY 0.829787 (-9020 3095);
PAINT SKYBLUE (-9020 3095);
DISPLAY INVISIBLE (-9020 3095);
FORCEPROP 2 LAST ROOM MEM_EFGH_DECOUPLING_CAPS
J 0
(-8975 3075);
DISPLAY 0.659574 (-8975 3075);
PAINT RED (-8975 3075);
DISPLAY INVISIBLE (-8975 3075);
FORCEPROP 1 LAST HDL_POWER GND
J 0
(-9000 3150);
DISPLAY 0.723404 (-9000 3150);
PAINT GREEN (-9000 3150);
DISPLAY INVISIBLE (-9000 3150);
FORCEADD Q_RES..1
R 2
(-8575 2250);
FORCEPROP 1 LAST LOCATION R291
J 2
(-8550 2275);
DISPLAY 0.489362 (-8550 2275);
PAINT SKYBLUE (-8550 2275);
FORCEPROP 0 LAST $SEC 1
J 0
(-8550 2325);
DISPLAY 0.680851 (-8550 2325);
PAINT MONO (-8550 2325);
DISPLAY INVISIBLE (-8550 2325);
FORCEPROP 0 LAST CDS_SEC 1
J 0
(-8550 2325);
DISPLAY 1.021277 (-8550 2325);
DISPLAY INVISIBLE (-8550 2325);
FORCEPROP 1 LASTPIN (-8475 2250) $PN 1
J 2
(-8487 2262);
DISPLAY 0.489362 (-8487 2262);
PAINT MONO (-8487 2262);
FORCEPROP 1 LASTPIN (-8675 2250) $PN 2
J 2
(-8637 2262);
DISPLAY 0.489362 (-8637 2262);
PAINT MONO (-8637 2262);
FORCEPROP 1 LAST VALUE 0
J 0
(-8575 2200);
DISPLAY 0.489362 (-8575 2200);
PAINT SKYBLUE (-8575 2200);
FORCEPROP 2 LAST BOM_COST MEM
J 0
(-8600 2400);
DISPLAY 0.744681 (-8600 2400);
PAINT WHITE (-8600 2400);
DISPLAY INVISIBLE (-8600 2400);
FORCEPROP 2 LAST CDS_LIB pure_quanta
J 0
(-8575 2250);
DISPLAY INVISIBLE (-8575 2250);
FORCEPROP 1 LAST PATH I525
J 2
(-8525 2400);
DISPLAY 0.978723 (-8525 2400);
PAINT WHITE (-8525 2400);
DISPLAY INVISIBLE (-8525 2400);
FORCEPROP 1 LAST WATTAGE 1/16W
J 0
(-8500 2175);
DISPLAY 0.489362 (-8500 2175);
PAINT SKYBLUE (-8500 2175);
DISPLAY INVISIBLE (-8500 2175);
FORCEPROP 1 LAST MATERIAL CHIP
J 0
(-8750 2225);
DISPLAY 0.489362 (-8750 2225);
PAINT SKYBLUE (-8750 2225);
DISPLAY INVISIBLE (-8750 2225);
FORCEPROP 1 LAST TOLERANCE 5%
J 2
(-8450 2225);
DISPLAY 0.489362 (-8450 2225);
PAINT SKYBLUE (-8450 2225);
DISPLAY INVISIBLE (-8450 2225);
FORCEPROP 1 LAST PART_NUMBER CS00002JB38
J 0
(-8675 2300);
DISPLAY 0.489362 (-8675 2300);
PAINT SKYBLUE (-8675 2300);
DISPLAY INVISIBLE (-8675 2300);
FORCEPROP 1 LAST PACK_TYPE 0402LF
J 0
(-8750 2175);
DISPLAY 0.489362 (-8750 2175);
PAINT SKYBLUE (-8750 2175);
DISPLAY INVISIBLE (-8750 2175);
FORCEPROP 2 LAST ROOM RST_CPU0_PLD_TO_DIMM
J 0
(-8600 2350);
DISPLAY 0.744681 (-8600 2350);
PAINT RED (-8600 2350);
DISPLAY INVISIBLE (-8600 2350);
FORCEADD Q_RES..2
R 2
(-8700 2400);
FORCEPROP 1 LAST LOCATION R88
J 2
(-8745 2525);
DISPLAY 0.489362 (-8745 2525);
PAINT SKYBLUE (-8745 2525);
FORCEPROP 0 LAST $SEC 1
J 0
(-8725 2575);
DISPLAY 0.680851 (-8725 2575);
PAINT MONO (-8725 2575);
DISPLAY INVISIBLE (-8725 2575);
FORCEPROP 0 LAST CDS_SEC 1
J 0
(-8725 2575);
DISPLAY 1.021277 (-8725 2575);
DISPLAY INVISIBLE (-8725 2575);
FORCEPROP 1 LASTPIN (-8700 2500) $PN 1
J 2
(-8705 2462);
DISPLAY 0.489362 (-8705 2462);
PAINT MONO (-8705 2462);
FORCEPROP 1 LASTPIN (-8700 2300) $PN 2
J 2
(-8705 2310);
DISPLAY 0.489362 (-8705 2310);
PAINT MONO (-8705 2310);
FORCEPROP 1 LAST PACK_TYPE 0402LF
J 2
(-8750 2350);
DISPLAY 0.489362 (-8750 2350);
PAINT SKYBLUE (-8750 2350);
FORCEPROP 1 LAST WATTAGE 1/16W
J 2
(-8750 2425);
DISPLAY 0.489362 (-8750 2425);
PAINT SKYBLUE (-8750 2425);
FORCEPROP 1 LAST PART_NUMBER TMP_QCS21002JB34
J 2
(-8750 2375);
DISPLAY 0.489362 (-8750 2375);
PAINT SKYBLUE (-8750 2375);
FORCEPROP 1 LAST MATERIAL CHIP
J 2
(-8750 2400);
DISPLAY 0.489362 (-8750 2400);
PAINT SKYBLUE (-8750 2400);
FORCEPROP 1 LAST TOLERANCE 5%
J 2
(-8750 2450);
DISPLAY 0.489362 (-8750 2450);
PAINT SKYBLUE (-8750 2450);
FORCEPROP 1 LAST VALUE 1K
J 2
(-8745 2475);
DISPLAY 0.489362 (-8745 2475);
PAINT SKYBLUE (-8745 2475);
FORCEPROP 2 LAST CDS_LIB pure_quanta
J 2
(-8700 2400);
DISPLAY INVISIBLE (-8700 2400);
FORCEPROP 2 LAST BOM_COST MEM
J 2
(-8750 2575);
DISPLAY 0.808511 (-8750 2575);
DISPLAY INVISIBLE (-8750 2575);
FORCEPROP 1 LAST PATH I526
J 2
(-8750 2575);
DISPLAY 0.978723 (-8750 2575);
PAINT WHITE (-8750 2575);
DISPLAY INVISIBLE (-8750 2575);
FORCEPROP 2 LAST ROOM MEM_CH_A_CPU0_DIMM1
J 2
(-8750 2625);
DISPLAY 0.808511 (-8750 2625);
PAINT RED (-8750 2625);
DISPLAY INVISIBLE (-8750 2625);
FORCEADD VCC_CORE..1
(-8700 2575);
FORCEPROP 3 LASTPIN (-8700 2525) SIG_NAME P3V3_STBY\g
J 0
(-8690 2535);
DISPLAY 0.659574 (-8690 2535);
PAINT MONO (-8690 2535);
DISPLAY INVISIBLE (-8690 2535);
FORCEPROP 1 LAST HDL_POWER P3V3_STBY
J 1
(-8700 2625);
DISPLAY 0.489362 (-8700 2625);
PAINT GREEN (-8700 2625);
FORCEPROP 2 LAST CDS_LIB mstr_symbols
J 0
(-8700 2575);
DISPLAY INVISIBLE (-8700 2575);
FORCEPROP 1 LAST PATH I527
J 0
(-8650 2600);
DISPLAY 0.872340 (-8650 2600);
PAINT AQUA (-8650 2600);
DISPLAY INVISIBLE (-8650 2600);
FORCEPROP 0 LAST VOLTAGE 3.3
J 0
(-8975 2725);
DISPLAY 1.021277 (-8975 2725);
PAINT SKYBLUE (-8975 2725);
DISPLAY INVISIBLE (-8975 2725);
FORCEPROP 2 LAST ROOM PVCCINFAON_CPU0_CTRL
J 0
(-8700 2675);
DISPLAY 0.808511 (-8700 2675);
PAINT RED (-8700 2675);
DISPLAY INVISIBLE (-8700 2675);
FORCEADD Q_RES..2
(-8450 2400);
FORCEPROP 1 LAST LOCATION R89
J 0
(-8405 2525);
DISPLAY 0.489362 (-8405 2525);
PAINT SKYBLUE (-8405 2525);
FORCEPROP 0 LAST $SEC 1
J 0
(-8400 2575);
DISPLAY 0.680851 (-8400 2575);
PAINT MONO (-8400 2575);
DISPLAY INVISIBLE (-8400 2575);
FORCEPROP 0 LAST CDS_SEC 1
J 0
(-8400 2575);
DISPLAY 1.021277 (-8400 2575);
DISPLAY INVISIBLE (-8400 2575);
FORCEPROP 1 LASTPIN (-8450 2500) $PN 1
J 0
(-8445 2462);
DISPLAY 0.489362 (-8445 2462);
PAINT MONO (-8445 2462);
FORCEPROP 1 LASTPIN (-8450 2300) $PN 2
J 0
(-8445 2310);
DISPLAY 0.489362 (-8445 2310);
PAINT MONO (-8445 2310);
FORCEPROP 1 LAST WATTAGE 1/16W
J 0
(-8400 2425);
DISPLAY 0.489362 (-8400 2425);
PAINT SKYBLUE (-8400 2425);
FORCEPROP 1 LAST MATERIAL EMPTY
J 0
(-8400 2400);
DISPLAY 0.489362 (-8400 2400);
PAINT RED (-8400 2400);
FORCEPROP 1 LAST VALUE 1K
J 0
(-8405 2475);
DISPLAY 0.489362 (-8405 2475);
PAINT SKYBLUE (-8405 2475);
FORCEPROP 1 LAST TOLERANCE 5%
J 0
(-8400 2450);
DISPLAY 0.489362 (-8400 2450);
PAINT SKYBLUE (-8400 2450);
FORCEPROP 1 LAST PACK_TYPE 0402LF
J 0
(-8400 2350);
DISPLAY 0.489362 (-8400 2350);
PAINT SKYBLUE (-8400 2350);
FORCEPROP 2 LAST CDS_LIB pure_quanta
J 2
(-8450 2400);
DISPLAY INVISIBLE (-8450 2400);
FORCEPROP 2 LAST BOM_COST MEM
J 0
(-8400 2575);
DISPLAY 0.808511 (-8400 2575);
DISPLAY INVISIBLE (-8400 2575);
FORCEPROP 1 LAST PATH I528
J 0
(-8400 2575);
DISPLAY 0.978723 (-8400 2575);
PAINT WHITE (-8400 2575);
DISPLAY INVISIBLE (-8400 2575);
FORCEPROP 1 LAST PART_NUMBER TMP_QCS21002JB34
J 0
(-8400 2375);
DISPLAY 0.489362 (-8400 2375);
PAINT SKYBLUE (-8400 2375);
DISPLAY INVISIBLE (-8400 2375);
FORCEPROP 2 LAST ROOM MEM_CH_A_CPU0_DIMM1
J 0
(-8400 2625);
DISPLAY 0.808511 (-8400 2625);
PAINT RED (-8400 2625);
DISPLAY INVISIBLE (-8400 2625);
FORCEADD VCC_CORE..1
(-8450 2575);
FORCEPROP 3 LASTPIN (-8450 2525) SIG_NAME P3V3_STBY\g
J 0
(-8440 2535);
DISPLAY 0.659574 (-8440 2535);
PAINT MONO (-8440 2535);
DISPLAY INVISIBLE (-8440 2535);
FORCEPROP 1 LAST HDL_POWER P3V3_STBY
J 1
(-8450 2625);
DISPLAY 0.489362 (-8450 2625);
PAINT GREEN (-8450 2625);
FORCEPROP 2 LAST CDS_LIB mstr_symbols
J 0
(-8450 2575);
DISPLAY INVISIBLE (-8450 2575);
FORCEPROP 1 LAST PATH I529
J 0
(-8400 2600);
DISPLAY 0.872340 (-8400 2600);
PAINT AQUA (-8400 2600);
DISPLAY INVISIBLE (-8400 2600);
FORCEPROP 0 LAST VOLTAGE 3.3
J 0
(-8725 2725);
DISPLAY 1.021277 (-8725 2725);
PAINT SKYBLUE (-8725 2725);
DISPLAY INVISIBLE (-8725 2725);
FORCEPROP 2 LAST ROOM PVCCINFAON_CPU0_CTRL
J 0
(-8450 2675);
DISPLAY 0.808511 (-8450 2675);
PAINT RED (-8450 2675);
DISPLAY INVISIBLE (-8450 2675);
FORCEADD Q_CAP..1
R 2
(-2375 6050);
FORCEPROP 1 LAST LOCATION C142
J 2
(-2425 6150);
DISPLAY 0.489362 (-2425 6150);
PAINT SKYBLUE (-2425 6150);
FORCEPROP 0 LAST $SEC 1
J 0
(-2425 6200);
DISPLAY 0.680851 (-2425 6200);
PAINT MONO (-2425 6200);
DISPLAY INVISIBLE (-2425 6200);
FORCEPROP 0 LAST CDS_SEC 1
J 0
(-2425 6200);
DISPLAY 0.680851 (-2425 6200);
DISPLAY INVISIBLE (-2425 6200);
FORCEPROP 1 LASTPIN (-2375 6150) $PN 1
J 2
(-2385 6130);
DISPLAY 0.489362 (-2385 6130);
PAINT MONO (-2385 6130);
FORCEPROP 1 LASTPIN (-2375 5950) $PN 2
J 2
(-2385 5930);
DISPLAY 0.489362 (-2385 5930);
PAINT MONO (-2385 5930);
FORCEPROP 1 LAST MATERIAL X6S
J 2
(-2425 5950);
DISPLAY 0.489362 (-2425 5950);
PAINT SKYBLUE (-2425 5950);
FORCEPROP 1 LAST TOLERANCE 10%
J 2
(-2425 6000);
DISPLAY 0.489362 (-2425 6000);
PAINT SKYBLUE (-2425 6000);
FORCEPROP 1 LAST VALUE 10UF
J 2
(-2425 6100);
DISPLAY 0.489362 (-2425 6100);
PAINT SKYBLUE (-2425 6100);
FORCEPROP 1 LAST PART_NUMBER CH6104KEA00
J 2
(-2425 5900);
DISPLAY 0.489362 (-2425 5900);
PAINT SKYBLUE (-2425 5900);
FORCEPROP 1 LAST VOLTAGE 25V
J 2
(-2425 6050);
DISPLAY 0.489362 (-2425 6050);
PAINT SKYBLUE (-2425 6050);
FORCEPROP 1 LAST PACK_TYPE C0805
J 2
(-2425 5850);
DISPLAY 0.489362 (-2425 5850);
PAINT SKYBLUE (-2425 5850);
FORCEPROP 2 LAST CDS_LIB pure_quanta
J 0
(-2375 6050);
DISPLAY INVISIBLE (-2375 6050);
FORCEPROP 0 LAST BOM_COST MEM
J 2
(-2430 6195);
DISPLAY 0.595745 (-2430 6195);
PAINT MONO (-2430 6195);
DISPLAY INVISIBLE (-2430 6195);
FORCEPROP 1 LAST PATH I534
J 2
(-2425 6200);
DISPLAY 0.978723 (-2425 6200);
PAINT WHITE (-2425 6200);
DISPLAY INVISIBLE (-2425 6200);
FORCEPROP 0 LAST ROOM MEM_CH_A_CPU0_DIMM1
J 2
(-2430 6195);
DISPLAY 0.595745 (-2430 6195);
PAINT RED (-2430 6195);
DISPLAY INVISIBLE (-2430 6195);
FORCEADD UNIVERSAL_POWER..1
(-2950 6375);
FORCEPROP 3 LASTPIN (-2950 6325) SIG_NAME P12V_MEM_1\g
J 0
(-2940 6335);
DISPLAY 0.659574 (-2940 6335);
PAINT MONO (-2940 6335);
DISPLAY INVISIBLE (-2940 6335);
FORCEPROP 1 LAST HDL_POWER P12V_MEM_1
J 1
(-2975 6425);
DISPLAY 0.489362 (-2975 6425);
PAINT GREEN (-2975 6425);
FORCEPROP 2 LAST BOM_COST VR_SYSTEM
J 0
(-2950 6475);
DISPLAY 0.617021 (-2950 6475);
PAINT PURPLE (-2950 6475);
DISPLAY INVISIBLE (-2950 6475);
FORCEPROP 2 LAST CDS_LIB pure_quanta_power
J 0
(-2950 6375);
DISPLAY INVISIBLE (-2950 6375);
FORCEPROP 1 LAST PATH I535
J 0
(-2900 6400);
DISPLAY 0.872340 (-2900 6400);
PAINT AQUA (-2900 6400);
DISPLAY INVISIBLE (-2900 6400);
FORCEADD SCONN288_DDR506112002KQ..1
(-6900 3675);
FORCEPROP 1 LAST LOCATION J1
J 0
(-7350 5675);
DISPLAY 0.574468 (-7350 5675);
PAINT SKYBLUE (-7350 5675);
FORCEPROP 0 LAST $SEC 1
J 0
(-7350 5825);
DISPLAY 0.680851 (-7350 5825);
PAINT MONO (-7350 5825);
DISPLAY INVISIBLE (-7350 5825);
FORCEPROP 0 LAST CDS_SEC 1
J 0
(-7350 5825);
DISPLAY 0.680851 (-7350 5825);
DISPLAY INVISIBLE (-7350 5825);
FORCEPROP 0 LASTPIN (-7500 3075) $PN 62
J 2
(-7510 3085);
DISPLAY 0.680851 (-7510 3085);
PAINT MONO (-7510 3085);
FORCEPROP 0 LASTPIN (-7500 5125) $PN 66
J 2
(-7510 5135);
DISPLAY 0.680851 (-7510 5135);
PAINT MONO (-7510 5135);
FORCEPROP 0 LASTPIN (-7500 4725) $PN 76
J 2
(-7510 4735);
DISPLAY 0.680851 (-7510 4735);
PAINT MONO (-7510 4735);
FORCEPROP 0 LASTPIN (-7500 5175) $PN 211
J 2
(-7510 5185);
DISPLAY 0.680851 (-7510 5185);
PAINT MONO (-7510 5185);
FORCEPROP 0 LASTPIN (-7500 4775) $PN 221
J 2
(-7510 4785);
DISPLAY 0.680851 (-7510 4785);
PAINT MONO (-7510 4785);
FORCEPROP 0 LASTPIN (-7500 5225) $PN 68
J 2
(-7510 5235);
DISPLAY 0.680851 (-7510 5235);
PAINT MONO (-7510 5235);
FORCEPROP 0 LASTPIN (-7500 4825) $PN 78
J 2
(-7510 4835);
DISPLAY 0.680851 (-7510 4835);
PAINT MONO (-7510 4835);
FORCEPROP 0 LASTPIN (-7500 5275) $PN 213
J 2
(-7510 5285);
DISPLAY 0.680851 (-7510 5285);
PAINT MONO (-7510 5285);
FORCEPROP 0 LASTPIN (-7500 4875) $PN 223
J 2
(-7510 4885);
DISPLAY 0.680851 (-7510 4885);
PAINT MONO (-7510 4885);
FORCEPROP 0 LASTPIN (-7500 5325) $PN 70
J 2
(-7510 5335);
DISPLAY 0.680851 (-7510 5335);
PAINT MONO (-7510 5335);
FORCEPROP 0 LASTPIN (-7500 4925) $PN 80
J 2
(-7510 4935);
DISPLAY 0.680851 (-7510 4935);
PAINT MONO (-7510 4935);
FORCEPROP 0 LASTPIN (-7500 5375) $PN 215
J 2
(-7510 5385);
DISPLAY 0.680851 (-7510 5385);
PAINT MONO (-7510 5385);
FORCEPROP 0 LASTPIN (-7500 4975) $PN 225
J 2
(-7510 4985);
DISPLAY 0.680851 (-7510 4985);
PAINT MONO (-7510 4985);
FORCEPROP 0 LASTPIN (-7500 5425) $PN 72
J 2
(-7510 5435);
DISPLAY 0.680851 (-7510 5435);
PAINT MONO (-7510 5435);
FORCEPROP 0 LASTPIN (-7500 5025) $PN 82
J 2
(-7510 5035);
DISPLAY 0.680851 (-7510 5035);
PAINT MONO (-7510 5035);
FORCEPROP 0 LASTPIN (-7500 3675) $PN 51
J 2
(-7510 3685);
DISPLAY 0.680851 (-7510 3685);
PAINT MONO (-7510 3685);
FORCEPROP 0 LASTPIN (-7500 3225) $PN 96
J 2
(-7510 3235);
DISPLAY 0.680851 (-7510 3235);
PAINT MONO (-7510 3235);
FORCEPROP 0 LASTPIN (-7500 3725) $PN 53
J 2
(-7510 3735);
DISPLAY 0.680851 (-7510 3735);
PAINT MONO (-7510 3735);
FORCEPROP 0 LASTPIN (-7500 3275) $PN 98
J 2
(-7510 3285);
DISPLAY 0.680851 (-7510 3285);
PAINT MONO (-7510 3285);
FORCEPROP 0 LASTPIN (-7500 3775) $PN 196
J 2
(-7510 3785);
DISPLAY 0.680851 (-7510 3785);
PAINT MONO (-7510 3785);
FORCEPROP 0 LASTPIN (-7500 3325) $PN 241
J 2
(-7510 3335);
DISPLAY 0.680851 (-7510 3335);
PAINT MONO (-7510 3335);
FORCEPROP 0 LASTPIN (-7500 3825) $PN 198
J 2
(-7510 3835);
DISPLAY 0.680851 (-7510 3835);
PAINT MONO (-7510 3835);
FORCEPROP 0 LASTPIN (-7500 3375) $PN 243
J 2
(-7510 3385);
DISPLAY 0.680851 (-7510 3385);
PAINT MONO (-7510 3385);
FORCEPROP 0 LASTPIN (-7500 3875) $PN 58
J 2
(-7510 3885);
DISPLAY 0.680851 (-7510 3885);
PAINT MONO (-7510 3885);
FORCEPROP 0 LASTPIN (-7500 3425) $PN 89
J 2
(-7510 3435);
DISPLAY 0.680851 (-7510 3435);
PAINT MONO (-7510 3435);
FORCEPROP 0 LASTPIN (-7500 3925) $PN 60
J 2
(-7510 3935);
DISPLAY 0.680851 (-7510 3935);
PAINT MONO (-7510 3935);
FORCEPROP 0 LASTPIN (-7500 3475) $PN 91
J 2
(-7510 3485);
DISPLAY 0.680851 (-7510 3485);
PAINT MONO (-7510 3485);
FORCEPROP 0 LASTPIN (-7500 3975) $PN 203
J 2
(-7510 3985);
DISPLAY 0.680851 (-7510 3985);
PAINT MONO (-7510 3985);
FORCEPROP 0 LASTPIN (-7500 3525) $PN 234
J 2
(-7510 3535);
DISPLAY 0.680851 (-7510 3535);
PAINT MONO (-7510 3535);
FORCEPROP 0 LASTPIN (-7500 4025) $PN 205
J 2
(-7510 4035);
DISPLAY 0.680851 (-7510 4035);
PAINT MONO (-7510 4035);
FORCEPROP 0 LASTPIN (-7500 3575) $PN 236
J 2
(-7510 3585);
DISPLAY 0.680851 (-7510 3585);
PAINT MONO (-7510 3585);
FORCEPROP 0 LASTPIN (-7500 4125) $PN 218
J 2
(-7510 4135);
DISPLAY 0.680851 (-7510 4135);
PAINT MONO (-7510 4135);
FORCEPROP 0 LASTPIN (-7500 4175) $PN 217
J 2
(-7510 4185);
DISPLAY 0.680851 (-7510 4185);
PAINT MONO (-7510 4185);
FORCEPROP 0 LASTPIN (-7500 4425) $PN 64
J 2
(-7510 4435);
DISPLAY 0.680851 (-7510 4435);
PAINT MONO (-7510 4435);
FORCEPROP 0 LASTPIN (-7500 4275) $PN 84
J 2
(-7510 4285);
DISPLAY 0.680851 (-7510 4285);
PAINT MONO (-7510 4285);
FORCEPROP 0 LASTPIN (-7500 4475) $PN 209
J 2
(-7510 4485);
DISPLAY 0.680851 (-7510 4485);
PAINT MONO (-7510 4485);
FORCEPROP 0 LASTPIN (-7500 4325) $PN 229
J 2
(-7510 4335);
DISPLAY 0.680851 (-7510 4335);
PAINT MONO (-7510 4335);
FORCEPROP 0 LASTPIN (-6300 3875) $PN 7
J 0
(-6290 3885);
DISPLAY 0.680851 (-6290 3885);
PAINT MONO (-6290 3885);
FORCEPROP 0 LASTPIN (-6300 2225) $PN 100
J 0
(-6290 2235);
DISPLAY 0.680851 (-6290 2235);
PAINT MONO (-6290 2235);
FORCEPROP 0 LASTPIN (-6300 3925) $PN 9
J 0
(-6290 3935);
DISPLAY 0.680851 (-6290 3935);
PAINT MONO (-6290 3935);
FORCEPROP 0 LASTPIN (-6300 2275) $PN 102
J 0
(-6290 2285);
DISPLAY 0.680851 (-6290 2285);
PAINT MONO (-6290 2285);
FORCEPROP 0 LASTPIN (-6300 3975) $PN 152
J 0
(-6290 3985);
DISPLAY 0.680851 (-6290 3985);
PAINT MONO (-6290 3985);
FORCEPROP 0 LASTPIN (-6300 2325) $PN 245
J 0
(-6290 2335);
DISPLAY 0.680851 (-6290 2335);
PAINT MONO (-6290 2335);
FORCEPROP 0 LASTPIN (-6300 4025) $PN 154
J 0
(-6290 4035);
DISPLAY 0.680851 (-6290 4035);
PAINT MONO (-6290 4035);
FORCEPROP 0 LASTPIN (-6300 2375) $PN 247
J 0
(-6290 2385);
DISPLAY 0.680851 (-6290 2385);
PAINT MONO (-6290 2385);
FORCEPROP 0 LASTPIN (-6300 4075) $PN 14
J 0
(-6290 4085);
DISPLAY 0.680851 (-6290 4085);
PAINT MONO (-6290 4085);
FORCEPROP 0 LASTPIN (-6300 2425) $PN 107
J 0
(-6290 2435);
DISPLAY 0.680851 (-6290 2435);
PAINT MONO (-6290 2435);
FORCEPROP 0 LASTPIN (-6300 4125) $PN 16
J 0
(-6290 4135);
DISPLAY 0.680851 (-6290 4135);
PAINT MONO (-6290 4135);
FORCEPROP 0 LASTPIN (-6300 2475) $PN 109
J 0
(-6290 2485);
DISPLAY 0.680851 (-6290 2485);
PAINT MONO (-6290 2485);
FORCEPROP 0 LASTPIN (-6300 4175) $PN 159
J 0
(-6290 4185);
DISPLAY 0.680851 (-6290 4185);
PAINT MONO (-6290 4185);
FORCEPROP 0 LASTPIN (-6300 2525) $PN 252
J 0
(-6290 2535);
DISPLAY 0.680851 (-6290 2535);
PAINT MONO (-6290 2535);
FORCEPROP 0 LASTPIN (-6300 4225) $PN 161
J 0
(-6290 4235);
DISPLAY 0.680851 (-6290 4235);
PAINT MONO (-6290 4235);
FORCEPROP 0 LASTPIN (-6300 2575) $PN 254
J 0
(-6290 2585);
DISPLAY 0.680851 (-6290 2585);
PAINT MONO (-6290 2585);
FORCEPROP 0 LASTPIN (-6300 4275) $PN 18
J 0
(-6290 4285);
DISPLAY 0.680851 (-6290 4285);
PAINT MONO (-6290 4285);
FORCEPROP 0 LASTPIN (-6300 2625) $PN 111
J 0
(-6290 2635);
DISPLAY 0.680851 (-6290 2635);
PAINT MONO (-6290 2635);
FORCEPROP 0 LASTPIN (-6300 4325) $PN 20
J 0
(-6290 4335);
DISPLAY 0.680851 (-6290 4335);
PAINT MONO (-6290 4335);
FORCEPROP 0 LASTPIN (-6300 2675) $PN 113
J 0
(-6290 2685);
DISPLAY 0.680851 (-6290 2685);
PAINT MONO (-6290 2685);
FORCEPROP 0 LASTPIN (-6300 4375) $PN 163
J 0
(-6290 4385);
DISPLAY 0.680851 (-6290 4385);
PAINT MONO (-6290 4385);
FORCEPROP 0 LASTPIN (-6300 2725) $PN 256
J 0
(-6290 2735);
DISPLAY 0.680851 (-6290 2735);
PAINT MONO (-6290 2735);
FORCEPROP 0 LASTPIN (-6300 4425) $PN 165
J 0
(-6290 4435);
DISPLAY 0.680851 (-6290 4435);
PAINT MONO (-6290 4435);
FORCEPROP 0 LASTPIN (-6300 2775) $PN 258
J 0
(-6290 2785);
DISPLAY 0.680851 (-6290 2785);
PAINT MONO (-6290 2785);
FORCEPROP 0 LASTPIN (-6300 4475) $PN 25
J 0
(-6290 4485);
DISPLAY 0.680851 (-6290 4485);
PAINT MONO (-6290 4485);
FORCEPROP 0 LASTPIN (-6300 2825) $PN 118
J 0
(-6290 2835);
DISPLAY 0.680851 (-6290 2835);
PAINT MONO (-6290 2835);
FORCEPROP 0 LASTPIN (-6300 4525) $PN 27
J 0
(-6290 4535);
DISPLAY 0.680851 (-6290 4535);
PAINT MONO (-6290 4535);
FORCEPROP 0 LASTPIN (-6300 2875) $PN 120
J 0
(-6290 2885);
DISPLAY 0.680851 (-6290 2885);
PAINT MONO (-6290 2885);
FORCEPROP 0 LASTPIN (-6300 4575) $PN 170
J 0
(-6290 4585);
DISPLAY 0.680851 (-6290 4585);
PAINT MONO (-6290 4585);
FORCEPROP 0 LASTPIN (-6300 2925) $PN 263
J 0
(-6290 2935);
DISPLAY 0.680851 (-6290 2935);
PAINT MONO (-6290 2935);
FORCEPROP 0 LASTPIN (-6300 4625) $PN 172
J 0
(-6290 4635);
DISPLAY 0.680851 (-6290 4635);
PAINT MONO (-6290 4635);
FORCEPROP 0 LASTPIN (-6300 2975) $PN 265
J 0
(-6290 2985);
DISPLAY 0.680851 (-6290 2985);
PAINT MONO (-6290 2985);
FORCEPROP 0 LASTPIN (-6300 4675) $PN 29
J 0
(-6290 4685);
DISPLAY 0.680851 (-6290 4685);
PAINT MONO (-6290 4685);
FORCEPROP 0 LASTPIN (-6300 3025) $PN 122
J 0
(-6290 3035);
DISPLAY 0.680851 (-6290 3035);
PAINT MONO (-6290 3035);
FORCEPROP 0 LASTPIN (-6300 4725) $PN 31
J 0
(-6290 4735);
DISPLAY 0.680851 (-6290 4735);
PAINT MONO (-6290 4735);
FORCEPROP 0 LASTPIN (-6300 3075) $PN 124
J 0
(-6290 3085);
DISPLAY 0.680851 (-6290 3085);
PAINT MONO (-6290 3085);
FORCEPROP 0 LASTPIN (-6300 4775) $PN 174
J 0
(-6290 4785);
DISPLAY 0.680851 (-6290 4785);
PAINT MONO (-6290 4785);
FORCEPROP 0 LASTPIN (-6300 3125) $PN 267
J 0
(-6290 3135);
DISPLAY 0.680851 (-6290 3135);
PAINT MONO (-6290 3135);
FORCEPROP 0 LASTPIN (-6300 4825) $PN 176
J 0
(-6290 4835);
DISPLAY 0.680851 (-6290 4835);
PAINT MONO (-6290 4835);
FORCEPROP 0 LASTPIN (-6300 3175) $PN 269
J 0
(-6290 3185);
DISPLAY 0.680851 (-6290 3185);
PAINT MONO (-6290 3185);
FORCEPROP 0 LASTPIN (-6300 4875) $PN 36
J 0
(-6290 4885);
DISPLAY 0.680851 (-6290 4885);
PAINT MONO (-6290 4885);
FORCEPROP 0 LASTPIN (-6300 3225) $PN 129
J 0
(-6290 3235);
DISPLAY 0.680851 (-6290 3235);
PAINT MONO (-6290 3235);
FORCEPROP 0 LASTPIN (-6300 4925) $PN 38
J 0
(-6290 4935);
DISPLAY 0.680851 (-6290 4935);
PAINT MONO (-6290 4935);
FORCEPROP 0 LASTPIN (-6300 3275) $PN 131
J 0
(-6290 3285);
DISPLAY 0.680851 (-6290 3285);
PAINT MONO (-6290 3285);
FORCEPROP 0 LASTPIN (-6300 4975) $PN 181
J 0
(-6290 4985);
DISPLAY 0.680851 (-6290 4985);
PAINT MONO (-6290 4985);
FORCEPROP 0 LASTPIN (-6300 3325) $PN 274
J 0
(-6290 3335);
DISPLAY 0.680851 (-6290 3335);
PAINT MONO (-6290 3335);
FORCEPROP 0 LASTPIN (-6300 5025) $PN 183
J 0
(-6290 5035);
DISPLAY 0.680851 (-6290 5035);
PAINT MONO (-6290 5035);
FORCEPROP 0 LASTPIN (-6300 3375) $PN 276
J 0
(-6290 3385);
DISPLAY 0.680851 (-6290 3385);
PAINT MONO (-6290 3385);
FORCEPROP 0 LASTPIN (-6300 5075) $PN 40
J 0
(-6290 5085);
DISPLAY 0.680851 (-6290 5085);
PAINT MONO (-6290 5085);
FORCEPROP 0 LASTPIN (-6300 3425) $PN 133
J 0
(-6290 3435);
DISPLAY 0.680851 (-6290 3435);
PAINT MONO (-6290 3435);
FORCEPROP 0 LASTPIN (-6300 5125) $PN 42
J 0
(-6290 5135);
DISPLAY 0.680851 (-6290 5135);
PAINT MONO (-6290 5135);
FORCEPROP 0 LASTPIN (-6300 3475) $PN 135
J 0
(-6290 3485);
DISPLAY 0.680851 (-6290 3485);
PAINT MONO (-6290 3485);
FORCEPROP 0 LASTPIN (-6300 5175) $PN 185
J 0
(-6290 5185);
DISPLAY 0.680851 (-6290 5185);
PAINT MONO (-6290 5185);
FORCEPROP 0 LASTPIN (-6300 3525) $PN 278
J 0
(-6290 3535);
DISPLAY 0.680851 (-6290 3535);
PAINT MONO (-6290 3535);
FORCEPROP 0 LASTPIN (-6300 5225) $PN 187
J 0
(-6290 5235);
DISPLAY 0.680851 (-6290 5235);
PAINT MONO (-6290 5235);
FORCEPROP 0 LASTPIN (-6300 3575) $PN 280
J 0
(-6290 3585);
DISPLAY 0.680851 (-6290 3585);
PAINT MONO (-6290 3585);
FORCEPROP 0 LASTPIN (-6300 5275) $PN 47
J 0
(-6290 5285);
DISPLAY 0.680851 (-6290 5285);
PAINT MONO (-6290 5285);
FORCEPROP 0 LASTPIN (-6300 3625) $PN 140
J 0
(-6290 3635);
DISPLAY 0.680851 (-6290 3635);
PAINT MONO (-6290 3635);
FORCEPROP 0 LASTPIN (-6300 5325) $PN 49
J 0
(-6290 5335);
DISPLAY 0.680851 (-6290 5335);
PAINT MONO (-6290 5335);
FORCEPROP 0 LASTPIN (-6300 3675) $PN 142
J 0
(-6290 3685);
DISPLAY 0.680851 (-6290 3685);
PAINT MONO (-6290 3685);
FORCEPROP 0 LASTPIN (-6300 5375) $PN 192
J 0
(-6290 5385);
DISPLAY 0.680851 (-6290 5385);
PAINT MONO (-6290 5385);
FORCEPROP 0 LASTPIN (-6300 3725) $PN 285
J 0
(-6290 3735);
DISPLAY 0.680851 (-6290 3735);
PAINT MONO (-6290 3735);
FORCEPROP 0 LASTPIN (-6300 5425) $PN 194
J 0
(-6290 5435);
DISPLAY 0.680851 (-6290 5435);
PAINT MONO (-6290 5435);
FORCEPROP 0 LASTPIN (-6300 3775) $PN 287
J 0
(-6290 3785);
DISPLAY 0.680851 (-6290 3785);
PAINT MONO (-6290 3785);
FORCEPROP 0 LASTPIN (-7500 2925) $PN 148
J 2
(-7510 2935);
DISPLAY 0.680851 (-7510 2935);
PAINT MONO (-7510 2935);
FORCEPROP 0 LASTPIN (-7500 2825) $PN 4
J 2
(-7510 2835);
DISPLAY 0.680851 (-7510 2835);
PAINT MONO (-7510 2835);
FORCEPROP 0 LASTPIN (-7500 2875) $PN 5
J 2
(-7510 2885);
DISPLAY 0.680851 (-7510 2885);
PAINT MONO (-7510 2885);
FORCEPROP 0 LASTPIN (-7500 2025) $PN 86
J 2
(-7510 2035);
DISPLAY 0.680851 (-7510 2035);
PAINT MONO (-7510 2035);
FORCEPROP 0 LASTPIN (-7500 1975) $PN 87
J 2
(-7510 1985);
DISPLAY 0.680851 (-7510 1985);
PAINT MONO (-7510 1985);
FORCEPROP 0 LASTPIN (-7500 4625) $PN 74
J 2
(-7510 4635);
DISPLAY 0.680851 (-7510 4635);
PAINT MONO (-7510 4635);
FORCEPROP 0 LASTPIN (-7500 4575) $PN 227
J 2
(-7510 4585);
DISPLAY 0.680851 (-7510 4585);
PAINT MONO (-7510 4585);
FORCEPROP 0 LASTPIN (-7500 2575) $PN 147
J 2
(-7510 2585);
DISPLAY 0.680851 (-7510 2585);
PAINT MONO (-7510 2585);
FORCEPROP 0 LASTPIN (-7500 3125) $PN 207
J 2
(-7510 3135);
DISPLAY 0.680851 (-7510 3135);
PAINT MONO (-7510 3135);
FORCEPROP 0 LASTPIN (-7500 2175) $PN 2
J 2
(-7510 2185);
DISPLAY 0.680851 (-7510 2185);
PAINT MONO (-7510 2185);
FORCEPROP 0 LASTPIN (-7500 2225) $PN 144
J 2
(-7510 2235);
DISPLAY 0.680851 (-7510 2235);
PAINT MONO (-7510 2235);
FORCEPROP 0 LASTPIN (-7500 2275) $PN 149
J 2
(-7510 2285);
DISPLAY 0.680851 (-7510 2285);
PAINT MONO (-7510 2285);
FORCEPROP 0 LASTPIN (-7500 2325) $PN 150
J 2
(-7510 2335);
DISPLAY 0.680851 (-7510 2335);
PAINT MONO (-7510 2335);
FORCEPROP 0 LASTPIN (-7500 2375) $PN 220
J 2
(-7510 2385);
DISPLAY 0.680851 (-7510 2385);
PAINT MONO (-7510 2385);
FORCEPROP 0 LASTPIN (-7500 2425) $PN 231
J 2
(-7510 2435);
DISPLAY 0.680851 (-7510 2435);
PAINT MONO (-7510 2435);
FORCEPROP 0 LASTPIN (-7500 2475) $PN 232
J 2
(-7510 2485);
DISPLAY 0.680851 (-7510 2485);
PAINT MONO (-7510 2485);
FORCEPROP 0 LASTPIN (-7500 2975) $PN 3
J 2
(-7510 2985);
DISPLAY 0.680851 (-7510 2985);
PAINT MONO (-7510 2985);
FORCEPROP 1 LAST MATERIAL IO
J 0
(-7350 5600);
DISPLAY 0.468085 (-7350 5600);
PAINT SKYBLUE (-7350 5600);
FORCEPROP 2 LAST PART_TYPE SMLF
J 0
(-7350 5775);
DISPLAY 0.680851 (-7350 5775);
FORCEPROP 0 LAST VALUE SCONN288_DDR506112002KQ
J 0
(-7350 5725);
DISPLAY 0.446809 (-7350 5725);
PAINT SKYBLUE (-7350 5725);
FORCEPROP 1 LAST PART_NUMBER DFHST8FS479
J 0
(-7350 5650);
DISPLAY 0.468085 (-7350 5650);
PAINT SKYBLUE (-7350 5650);
FORCEPROP 1 LAST NEEDS_NO_SIZE TRUE
J 0
(-6900 3675);
DISPLAY 0.723404 (-6900 3675);
PAINT GREEN (-6900 3675);
DISPLAY INVISIBLE (-6900 3675);
FORCEPROP 1 LAST CDS_LMAN_SYM_OUTLINE -450,1900,450,-1850
J 0
(-6900 3675);
DISPLAY 0.468085 (-6900 3675);
PAINT GREEN (-6900 3675);
DISPLAY INVISIBLE (-6900 3675);
FORCEPROP 1 LAST PATH I536
J 0
(-6900 3675);
DISPLAY 0.723404 (-6900 3675);
PAINT GREEN (-6900 3675);
DISPLAY INVISIBLE (-6900 3675);
FORCEPROP 2 LAST CDS_LIB pure_quanta
J 0
(-6900 3675);
DISPLAY INVISIBLE (-6900 3675);
FORCEADD SCONN288_DDR506112002KQ..2
(-4600 4375);
FORCEPROP 1 LAST LOCATION J1
J 0
(-5200 5675);
DISPLAY 0.468085 (-5200 5675);
PAINT SKYBLUE (-5200 5675);
FORCEPROP 0 LAST $SEC 2
J 0
(-5200 5850);
DISPLAY 0.680851 (-5200 5850);
PAINT MONO (-5200 5850);
DISPLAY INVISIBLE (-5200 5850);
FORCEPROP 0 LAST CDS_SEC 2
J 0
(-5200 5850);
DISPLAY 0.680851 (-5200 5850);
DISPLAY INVISIBLE (-5200 5850);
FORCEPROP 0 LASTPIN (-3850 4425) $PN 12
J 0
(-3840 4435);
DISPLAY 0.680851 (-3840 4435);
PAINT MONO (-3840 4435);
FORCEPROP 0 LASTPIN (-3850 4475) $PN 11
J 0
(-3840 4485);
DISPLAY 0.680851 (-3840 4485);
PAINT MONO (-3840 4485);
FORCEPROP 0 LASTPIN (-3850 3375) $PN 105
J 0
(-3840 3385);
DISPLAY 0.680851 (-3840 3385);
PAINT MONO (-3840 3385);
FORCEPROP 0 LASTPIN (-3850 3425) $PN 104
J 0
(-3840 3435);
DISPLAY 0.680851 (-3840 3435);
PAINT MONO (-3840 3435);
FORCEPROP 0 LASTPIN (-3850 4525) $PN 23
J 0
(-3840 4535);
DISPLAY 0.680851 (-3840 4535);
PAINT MONO (-3840 4535);
FORCEPROP 0 LASTPIN (-3850 4575) $PN 22
J 0
(-3840 4585);
DISPLAY 0.680851 (-3840 4585);
PAINT MONO (-3840 4585);
FORCEPROP 0 LASTPIN (-3850 3475) $PN 116
J 0
(-3840 3485);
DISPLAY 0.680851 (-3840 3485);
PAINT MONO (-3840 3485);
FORCEPROP 0 LASTPIN (-3850 3525) $PN 115
J 0
(-3840 3535);
DISPLAY 0.680851 (-3840 3535);
PAINT MONO (-3840 3535);
FORCEPROP 0 LASTPIN (-3850 4625) $PN 34
J 0
(-3840 4635);
DISPLAY 0.680851 (-3840 4635);
PAINT MONO (-3840 4635);
FORCEPROP 0 LASTPIN (-3850 4675) $PN 33
J 0
(-3840 4685);
DISPLAY 0.680851 (-3840 4685);
PAINT MONO (-3840 4685);
FORCEPROP 0 LASTPIN (-3850 3575) $PN 127
J 0
(-3840 3585);
DISPLAY 0.680851 (-3840 3585);
PAINT MONO (-3840 3585);
FORCEPROP 0 LASTPIN (-3850 3625) $PN 126
J 0
(-3840 3635);
DISPLAY 0.680851 (-3840 3635);
PAINT MONO (-3840 3635);
FORCEPROP 0 LASTPIN (-3850 4725) $PN 45
J 0
(-3840 4735);
DISPLAY 0.680851 (-3840 4735);
PAINT MONO (-3840 4735);
FORCEPROP 0 LASTPIN (-3850 4775) $PN 44
J 0
(-3840 4785);
DISPLAY 0.680851 (-3840 4785);
PAINT MONO (-3840 4785);
FORCEPROP 0 LASTPIN (-3850 3675) $PN 138
J 0
(-3840 3685);
DISPLAY 0.680851 (-3840 3685);
PAINT MONO (-3840 3685);
FORCEPROP 0 LASTPIN (-3850 3725) $PN 137
J 0
(-3840 3735);
DISPLAY 0.680851 (-3840 3735);
PAINT MONO (-3840 3735);
FORCEPROP 0 LASTPIN (-3850 4825) $PN 56
J 0
(-3840 4835);
DISPLAY 0.680851 (-3840 4835);
PAINT MONO (-3840 4835);
FORCEPROP 0 LASTPIN (-3850 4875) $PN 55
J 0
(-3840 4885);
DISPLAY 0.680851 (-3840 4885);
PAINT MONO (-3840 4885);
FORCEPROP 0 LASTPIN (-3850 3775) $PN 238
J 0
(-3840 3785);
DISPLAY 0.680851 (-3840 3785);
PAINT MONO (-3840 3785);
FORCEPROP 0 LASTPIN (-3850 3825) $PN 239
J 0
(-3840 3835);
DISPLAY 0.680851 (-3840 3835);
PAINT MONO (-3840 3835);
FORCEPROP 0 LASTPIN (-3850 4925) $PN 156
J 0
(-3840 4935);
DISPLAY 0.680851 (-3840 4935);
PAINT MONO (-3840 4935);
FORCEPROP 0 LASTPIN (-3850 4975) $PN 157
J 0
(-3840 4985);
DISPLAY 0.680851 (-3840 4985);
PAINT MONO (-3840 4985);
FORCEPROP 0 LASTPIN (-3850 3875) $PN 249
J 0
(-3840 3885);
DISPLAY 0.680851 (-3840 3885);
PAINT MONO (-3840 3885);
FORCEPROP 0 LASTPIN (-3850 3925) $PN 250
J 0
(-3840 3935);
DISPLAY 0.680851 (-3840 3935);
PAINT MONO (-3840 3935);
FORCEPROP 0 LASTPIN (-3850 5025) $PN 167
J 0
(-3840 5035);
DISPLAY 0.680851 (-3840 5035);
PAINT MONO (-3840 5035);
FORCEPROP 0 LASTPIN (-3850 5075) $PN 168
J 0
(-3840 5085);
DISPLAY 0.680851 (-3840 5085);
PAINT MONO (-3840 5085);
FORCEPROP 0 LASTPIN (-3850 3975) $PN 260
J 0
(-3840 3985);
DISPLAY 0.680851 (-3840 3985);
PAINT MONO (-3840 3985);
FORCEPROP 0 LASTPIN (-3850 4025) $PN 261
J 0
(-3840 4035);
DISPLAY 0.680851 (-3840 4035);
PAINT MONO (-3840 4035);
FORCEPROP 0 LASTPIN (-3850 5125) $PN 178
J 0
(-3840 5135);
DISPLAY 0.680851 (-3840 5135);
PAINT MONO (-3840 5135);
FORCEPROP 0 LASTPIN (-3850 5175) $PN 179
J 0
(-3840 5185);
DISPLAY 0.680851 (-3840 5185);
PAINT MONO (-3840 5185);
FORCEPROP 0 LASTPIN (-3850 4075) $PN 271
J 0
(-3840 4085);
DISPLAY 0.680851 (-3840 4085);
PAINT MONO (-3840 4085);
FORCEPROP 0 LASTPIN (-3850 4125) $PN 272
J 0
(-3840 4135);
DISPLAY 0.680851 (-3840 4135);
PAINT MONO (-3840 4135);
FORCEPROP 0 LASTPIN (-3850 5225) $PN 189
J 0
(-3840 5235);
DISPLAY 0.680851 (-3840 5235);
PAINT MONO (-3840 5235);
FORCEPROP 0 LASTPIN (-3850 5275) $PN 190
J 0
(-3840 5285);
DISPLAY 0.680851 (-3840 5285);
PAINT MONO (-3840 5285);
FORCEPROP 0 LASTPIN (-3850 4175) $PN 282
J 0
(-3840 4185);
DISPLAY 0.680851 (-3840 4185);
PAINT MONO (-3840 4185);
FORCEPROP 0 LASTPIN (-3850 4225) $PN 283
J 0
(-3840 4235);
DISPLAY 0.680851 (-3840 4235);
PAINT MONO (-3840 4235);
FORCEPROP 0 LASTPIN (-3850 5325) $PN 200
J 0
(-3840 5335);
DISPLAY 0.680851 (-3840 5335);
PAINT MONO (-3840 5335);
FORCEPROP 0 LASTPIN (-3850 5375) $PN 201
J 0
(-3840 5385);
DISPLAY 0.680851 (-3840 5385);
PAINT MONO (-3840 5385);
FORCEPROP 0 LASTPIN (-3850 4275) $PN 94
J 0
(-3840 4285);
DISPLAY 0.680851 (-3840 4285);
PAINT MONO (-3840 4285);
FORCEPROP 0 LASTPIN (-3850 4325) $PN 93
J 0
(-3840 4335);
DISPLAY 0.680851 (-3840 4335);
PAINT MONO (-3840 4335);
FORCEPROP 1 LAST MATERIAL IO
J 0
(-5200 5550);
DISPLAY 0.468085 (-5200 5550);
PAINT SKYBLUE (-5200 5550);
FORCEPROP 2 LAST PART_TYPE SMLF
J 0
(-5200 5800);
DISPLAY 0.680851 (-5200 5800);
FORCEPROP 2 LAST VALUE SCONN288_DDR506112002KQ
J 0
(-5200 5725);
DISPLAY 0.446809 (-5200 5725);
PAINT SKYBLUE (-5200 5725);
FORCEPROP 1 LAST PART_NUMBER DFHST8FS479
J 0
(-5200 5625);
DISPLAY 0.468085 (-5200 5625);
PAINT SKYBLUE (-5200 5625);
FORCEPROP 1 LAST NEEDS_NO_SIZE TRUE
J 0
(-4600 4375);
DISPLAY 0.723404 (-4600 4375);
PAINT GREEN (-4600 4375);
DISPLAY INVISIBLE (-4600 4375);
FORCEPROP 1 LAST CDS_LMAN_SYM_OUTLINE -600,1150,600,-1150
J 0
(-4600 4375);
DISPLAY 0.468085 (-4600 4375);
PAINT GREEN (-4600 4375);
DISPLAY INVISIBLE (-4600 4375);
FORCEPROP 1 LAST PATH I537
J 0
(-4600 4375);
DISPLAY 0.723404 (-4600 4375);
PAINT GREEN (-4600 4375);
DISPLAY INVISIBLE (-4600 4375);
FORCEPROP 2 LAST CDS_LIB pure_quanta
J 0
(-4600 4375);
DISPLAY INVISIBLE (-4600 4375);
FORCEADD SCONN288_DDR506112002KQ..3
(-1450 3700);
FORCEPROP 1 LAST LOCATION J1
J 0
(-1900 5650);
DISPLAY 0.468085 (-1900 5650);
PAINT SKYBLUE (-1900 5650);
FORCEPROP 0 LAST $SEC 3
J 0
(-1900 5825);
DISPLAY 0.680851 (-1900 5825);
PAINT MONO (-1900 5825);
DISPLAY INVISIBLE (-1900 5825);
FORCEPROP 0 LAST CDS_SEC 3
J 0
(-1900 5825);
DISPLAY 0.680851 (-1900 5825);
DISPLAY INVISIBLE (-1900 5825);
FORCEPROP 0 LASTPIN (-850 2100) $PN G1
J 0
(-840 2110);
DISPLAY 0.680851 (-840 2110);
PAINT MONO (-840 2110);
FORCEPROP 0 LASTPIN (-850 2050) $PN G2
J 0
(-840 2060);
DISPLAY 0.680851 (-840 2060);
PAINT MONO (-840 2060);
FORCEPROP 0 LASTPIN (-850 2000) $PN G3
J 0
(-840 2010);
DISPLAY 0.680851 (-840 2010);
PAINT MONO (-840 2010);
FORCEPROP 0 LASTPIN (-2050 5250) $PN 1
J 2
(-2060 5260);
DISPLAY 0.680851 (-2060 5260);
PAINT MONO (-2060 5260);
FORCEPROP 0 LASTPIN (-2050 5300) $PN 145
J 2
(-2060 5310);
DISPLAY 0.680851 (-2060 5310);
PAINT MONO (-2060 5310);
FORCEPROP 0 LASTPIN (-2050 5350) $PN 146
J 2
(-2060 5360);
DISPLAY 0.680851 (-2060 5360);
PAINT MONO (-2060 5360);
FORCEPROP 0 LASTPIN (-850 2200) $PN 6
J 0
(-840 2210);
DISPLAY 0.680851 (-840 2210);
PAINT MONO (-840 2210);
FORCEPROP 0 LASTPIN (-850 2250) $PN 8
J 0
(-840 2260);
DISPLAY 0.680851 (-840 2260);
PAINT MONO (-840 2260);
FORCEPROP 0 LASTPIN (-850 2300) $PN 10
J 0
(-840 2310);
DISPLAY 0.680851 (-840 2310);
PAINT MONO (-840 2310);
FORCEPROP 0 LASTPIN (-850 2350) $PN 13
J 0
(-840 2360);
DISPLAY 0.680851 (-840 2360);
PAINT MONO (-840 2360);
FORCEPROP 0 LASTPIN (-850 2400) $PN 15
J 0
(-840 2410);
DISPLAY 0.680851 (-840 2410);
PAINT MONO (-840 2410);
FORCEPROP 0 LASTPIN (-850 2450) $PN 17
J 0
(-840 2460);
DISPLAY 0.680851 (-840 2460);
PAINT MONO (-840 2460);
FORCEPROP 0 LASTPIN (-850 2500) $PN 19
J 0
(-840 2510);
DISPLAY 0.680851 (-840 2510);
PAINT MONO (-840 2510);
FORCEPROP 0 LASTPIN (-850 2550) $PN 21
J 0
(-840 2560);
DISPLAY 0.680851 (-840 2560);
PAINT MONO (-840 2560);
FORCEPROP 0 LASTPIN (-850 2600) $PN 24
J 0
(-840 2610);
DISPLAY 0.680851 (-840 2610);
PAINT MONO (-840 2610);
FORCEPROP 0 LASTPIN (-850 2650) $PN 26
J 0
(-840 2660);
DISPLAY 0.680851 (-840 2660);
PAINT MONO (-840 2660);
FORCEPROP 0 LASTPIN (-850 2700) $PN 28
J 0
(-840 2710);
DISPLAY 0.680851 (-840 2710);
PAINT MONO (-840 2710);
FORCEPROP 0 LASTPIN (-850 2750) $PN 30
J 0
(-840 2760);
DISPLAY 0.680851 (-840 2760);
PAINT MONO (-840 2760);
FORCEPROP 0 LASTPIN (-850 2800) $PN 32
J 0
(-840 2810);
DISPLAY 0.680851 (-840 2810);
PAINT MONO (-840 2810);
FORCEPROP 0 LASTPIN (-850 2850) $PN 35
J 0
(-840 2860);
DISPLAY 0.680851 (-840 2860);
PAINT MONO (-840 2860);
FORCEPROP 0 LASTPIN (-850 2900) $PN 37
J 0
(-840 2910);
DISPLAY 0.680851 (-840 2910);
PAINT MONO (-840 2910);
FORCEPROP 0 LASTPIN (-850 2950) $PN 39
J 0
(-840 2960);
DISPLAY 0.680851 (-840 2960);
PAINT MONO (-840 2960);
FORCEPROP 0 LASTPIN (-850 3000) $PN 41
J 0
(-840 3010);
DISPLAY 0.680851 (-840 3010);
PAINT MONO (-840 3010);
FORCEPROP 0 LASTPIN (-850 3050) $PN 43
J 0
(-840 3060);
DISPLAY 0.680851 (-840 3060);
PAINT MONO (-840 3060);
FORCEPROP 0 LASTPIN (-850 3100) $PN 46
J 0
(-840 3110);
DISPLAY 0.680851 (-840 3110);
PAINT MONO (-840 3110);
FORCEPROP 0 LASTPIN (-850 3150) $PN 48
J 0
(-840 3160);
DISPLAY 0.680851 (-840 3160);
PAINT MONO (-840 3160);
FORCEPROP 0 LASTPIN (-850 3200) $PN 50
J 0
(-840 3210);
DISPLAY 0.680851 (-840 3210);
PAINT MONO (-840 3210);
FORCEPROP 0 LASTPIN (-850 3250) $PN 52
J 0
(-840 3260);
DISPLAY 0.680851 (-840 3260);
PAINT MONO (-840 3260);
FORCEPROP 0 LASTPIN (-850 3300) $PN 54
J 0
(-840 3310);
DISPLAY 0.680851 (-840 3310);
PAINT MONO (-840 3310);
FORCEPROP 0 LASTPIN (-850 3350) $PN 57
J 0
(-840 3360);
DISPLAY 0.680851 (-840 3360);
PAINT MONO (-840 3360);
FORCEPROP 0 LASTPIN (-850 3400) $PN 59
J 0
(-840 3410);
DISPLAY 0.680851 (-840 3410);
PAINT MONO (-840 3410);
FORCEPROP 0 LASTPIN (-850 3450) $PN 61
J 0
(-840 3460);
DISPLAY 0.680851 (-840 3460);
PAINT MONO (-840 3460);
FORCEPROP 0 LASTPIN (-850 3500) $PN 63
J 0
(-840 3510);
DISPLAY 0.680851 (-840 3510);
PAINT MONO (-840 3510);
FORCEPROP 0 LASTPIN (-850 3550) $PN 65
J 0
(-840 3560);
DISPLAY 0.680851 (-840 3560);
PAINT MONO (-840 3560);
FORCEPROP 0 LASTPIN (-850 3600) $PN 67
J 0
(-840 3610);
DISPLAY 0.680851 (-840 3610);
PAINT MONO (-840 3610);
FORCEPROP 0 LASTPIN (-850 3650) $PN 69
J 0
(-840 3660);
DISPLAY 0.680851 (-840 3660);
PAINT MONO (-840 3660);
FORCEPROP 0 LASTPIN (-850 3700) $PN 71
J 0
(-840 3710);
DISPLAY 0.680851 (-840 3710);
PAINT MONO (-840 3710);
FORCEPROP 0 LASTPIN (-850 3750) $PN 73
J 0
(-840 3760);
DISPLAY 0.680851 (-840 3760);
PAINT MONO (-840 3760);
FORCEPROP 0 LASTPIN (-850 3800) $PN 75
J 0
(-840 3810);
DISPLAY 0.680851 (-840 3810);
PAINT MONO (-840 3810);
FORCEPROP 0 LASTPIN (-850 3850) $PN 77
J 0
(-840 3860);
DISPLAY 0.680851 (-840 3860);
PAINT MONO (-840 3860);
FORCEPROP 0 LASTPIN (-850 3900) $PN 79
J 0
(-840 3910);
DISPLAY 0.680851 (-840 3910);
PAINT MONO (-840 3910);
FORCEPROP 0 LASTPIN (-850 3950) $PN 81
J 0
(-840 3960);
DISPLAY 0.680851 (-840 3960);
PAINT MONO (-840 3960);
FORCEPROP 0 LASTPIN (-850 4000) $PN 83
J 0
(-840 4010);
DISPLAY 0.680851 (-840 4010);
PAINT MONO (-840 4010);
FORCEPROP 0 LASTPIN (-850 4050) $PN 85
J 0
(-840 4060);
DISPLAY 0.680851 (-840 4060);
PAINT MONO (-840 4060);
FORCEPROP 0 LASTPIN (-850 4100) $PN 88
J 0
(-840 4110);
DISPLAY 0.680851 (-840 4110);
PAINT MONO (-840 4110);
FORCEPROP 0 LASTPIN (-850 4150) $PN 90
J 0
(-840 4160);
DISPLAY 0.680851 (-840 4160);
PAINT MONO (-840 4160);
FORCEPROP 0 LASTPIN (-850 4200) $PN 92
J 0
(-840 4210);
DISPLAY 0.680851 (-840 4210);
PAINT MONO (-840 4210);
FORCEPROP 0 LASTPIN (-850 4250) $PN 95
J 0
(-840 4260);
DISPLAY 0.680851 (-840 4260);
PAINT MONO (-840 4260);
FORCEPROP 0 LASTPIN (-850 4300) $PN 97
J 0
(-840 4310);
DISPLAY 0.680851 (-840 4310);
PAINT MONO (-840 4310);
FORCEPROP 0 LASTPIN (-850 4350) $PN 99
J 0
(-840 4360);
DISPLAY 0.680851 (-840 4360);
PAINT MONO (-840 4360);
FORCEPROP 0 LASTPIN (-850 4400) $PN 101
J 0
(-840 4410);
DISPLAY 0.680851 (-840 4410);
PAINT MONO (-840 4410);
FORCEPROP 0 LASTPIN (-850 4450) $PN 103
J 0
(-840 4460);
DISPLAY 0.680851 (-840 4460);
PAINT MONO (-840 4460);
FORCEPROP 0 LASTPIN (-850 4500) $PN 106
J 0
(-840 4510);
DISPLAY 0.680851 (-840 4510);
PAINT MONO (-840 4510);
FORCEPROP 0 LASTPIN (-850 4550) $PN 108
J 0
(-840 4560);
DISPLAY 0.680851 (-840 4560);
PAINT MONO (-840 4560);
FORCEPROP 0 LASTPIN (-850 4600) $PN 110
J 0
(-840 4610);
DISPLAY 0.680851 (-840 4610);
PAINT MONO (-840 4610);
FORCEPROP 0 LASTPIN (-850 4650) $PN 112
J 0
(-840 4660);
DISPLAY 0.680851 (-840 4660);
PAINT MONO (-840 4660);
FORCEPROP 0 LASTPIN (-850 4700) $PN 114
J 0
(-840 4710);
DISPLAY 0.680851 (-840 4710);
PAINT MONO (-840 4710);
FORCEPROP 0 LASTPIN (-850 4750) $PN 117
J 0
(-840 4760);
DISPLAY 0.680851 (-840 4760);
PAINT MONO (-840 4760);
FORCEPROP 0 LASTPIN (-850 4800) $PN 119
J 0
(-840 4810);
DISPLAY 0.680851 (-840 4810);
PAINT MONO (-840 4810);
FORCEPROP 0 LASTPIN (-850 4850) $PN 121
J 0
(-840 4860);
DISPLAY 0.680851 (-840 4860);
PAINT MONO (-840 4860);
FORCEPROP 0 LASTPIN (-850 4900) $PN 123
J 0
(-840 4910);
DISPLAY 0.680851 (-840 4910);
PAINT MONO (-840 4910);
FORCEPROP 0 LASTPIN (-850 4950) $PN 125
J 0
(-840 4960);
DISPLAY 0.680851 (-840 4960);
PAINT MONO (-840 4960);
FORCEPROP 0 LASTPIN (-850 5000) $PN 128
J 0
(-840 5010);
DISPLAY 0.680851 (-840 5010);
PAINT MONO (-840 5010);
FORCEPROP 0 LASTPIN (-850 5050) $PN 130
J 0
(-840 5060);
DISPLAY 0.680851 (-840 5060);
PAINT MONO (-840 5060);
FORCEPROP 0 LASTPIN (-850 5100) $PN 132
J 0
(-840 5110);
DISPLAY 0.680851 (-840 5110);
PAINT MONO (-840 5110);
FORCEPROP 0 LASTPIN (-850 5150) $PN 134
J 0
(-840 5160);
DISPLAY 0.680851 (-840 5160);
PAINT MONO (-840 5160);
FORCEPROP 0 LASTPIN (-850 5200) $PN 136
J 0
(-840 5210);
DISPLAY 0.680851 (-840 5210);
PAINT MONO (-840 5210);
FORCEPROP 0 LASTPIN (-850 5250) $PN 139
J 0
(-840 5260);
DISPLAY 0.680851 (-840 5260);
PAINT MONO (-840 5260);
FORCEPROP 0 LASTPIN (-850 5300) $PN 141
J 0
(-840 5310);
DISPLAY 0.680851 (-840 5310);
PAINT MONO (-840 5310);
FORCEPROP 0 LASTPIN (-850 5350) $PN 143
J 0
(-840 5360);
DISPLAY 0.680851 (-840 5360);
PAINT MONO (-840 5360);
FORCEPROP 0 LASTPIN (-2050 2100) $PN 151
J 2
(-2060 2110);
DISPLAY 0.680851 (-2060 2110);
PAINT MONO (-2060 2110);
FORCEPROP 0 LASTPIN (-2050 2150) $PN 153
J 2
(-2060 2160);
DISPLAY 0.680851 (-2060 2160);
PAINT MONO (-2060 2160);
FORCEPROP 0 LASTPIN (-2050 2200) $PN 155
J 2
(-2060 2210);
DISPLAY 0.680851 (-2060 2210);
PAINT MONO (-2060 2210);
FORCEPROP 0 LASTPIN (-2050 2250) $PN 158
J 2
(-2060 2260);
DISPLAY 0.680851 (-2060 2260);
PAINT MONO (-2060 2260);
FORCEPROP 0 LASTPIN (-2050 2300) $PN 160
J 2
(-2060 2310);
DISPLAY 0.680851 (-2060 2310);
PAINT MONO (-2060 2310);
FORCEPROP 0 LASTPIN (-2050 2350) $PN 162
J 2
(-2060 2360);
DISPLAY 0.680851 (-2060 2360);
PAINT MONO (-2060 2360);
FORCEPROP 0 LASTPIN (-2050 2400) $PN 164
J 2
(-2060 2410);
DISPLAY 0.680851 (-2060 2410);
PAINT MONO (-2060 2410);
FORCEPROP 0 LASTPIN (-2050 2450) $PN 166
J 2
(-2060 2460);
DISPLAY 0.680851 (-2060 2460);
PAINT MONO (-2060 2460);
FORCEPROP 0 LASTPIN (-2050 2500) $PN 169
J 2
(-2060 2510);
DISPLAY 0.680851 (-2060 2510);
PAINT MONO (-2060 2510);
FORCEPROP 0 LASTPIN (-2050 2550) $PN 171
J 2
(-2060 2560);
DISPLAY 0.680851 (-2060 2560);
PAINT MONO (-2060 2560);
FORCEPROP 0 LASTPIN (-2050 2600) $PN 173
J 2
(-2060 2610);
DISPLAY 0.680851 (-2060 2610);
PAINT MONO (-2060 2610);
FORCEPROP 0 LASTPIN (-2050 2650) $PN 175
J 2
(-2060 2660);
DISPLAY 0.680851 (-2060 2660);
PAINT MONO (-2060 2660);
FORCEPROP 0 LASTPIN (-2050 2700) $PN 177
J 2
(-2060 2710);
DISPLAY 0.680851 (-2060 2710);
PAINT MONO (-2060 2710);
FORCEPROP 0 LASTPIN (-2050 2750) $PN 180
J 2
(-2060 2760);
DISPLAY 0.680851 (-2060 2760);
PAINT MONO (-2060 2760);
FORCEPROP 0 LASTPIN (-2050 2800) $PN 182
J 2
(-2060 2810);
DISPLAY 0.680851 (-2060 2810);
PAINT MONO (-2060 2810);
FORCEPROP 0 LASTPIN (-2050 2850) $PN 184
J 2
(-2060 2860);
DISPLAY 0.680851 (-2060 2860);
PAINT MONO (-2060 2860);
FORCEPROP 0 LASTPIN (-2050 2900) $PN 186
J 2
(-2060 2910);
DISPLAY 0.680851 (-2060 2910);
PAINT MONO (-2060 2910);
FORCEPROP 0 LASTPIN (-2050 2950) $PN 188
J 2
(-2060 2960);
DISPLAY 0.680851 (-2060 2960);
PAINT MONO (-2060 2960);
FORCEPROP 0 LASTPIN (-2050 3000) $PN 191
J 2
(-2060 3010);
DISPLAY 0.680851 (-2060 3010);
PAINT MONO (-2060 3010);
FORCEPROP 0 LASTPIN (-2050 3050) $PN 193
J 2
(-2060 3060);
DISPLAY 0.680851 (-2060 3060);
PAINT MONO (-2060 3060);
FORCEPROP 0 LASTPIN (-2050 3100) $PN 195
J 2
(-2060 3110);
DISPLAY 0.680851 (-2060 3110);
PAINT MONO (-2060 3110);
FORCEPROP 0 LASTPIN (-2050 3150) $PN 197
J 2
(-2060 3160);
DISPLAY 0.680851 (-2060 3160);
PAINT MONO (-2060 3160);
FORCEPROP 0 LASTPIN (-2050 3200) $PN 199
J 2
(-2060 3210);
DISPLAY 0.680851 (-2060 3210);
PAINT MONO (-2060 3210);
FORCEPROP 0 LASTPIN (-2050 3250) $PN 202
J 2
(-2060 3260);
DISPLAY 0.680851 (-2060 3260);
PAINT MONO (-2060 3260);
FORCEPROP 0 LASTPIN (-2050 3300) $PN 204
J 2
(-2060 3310);
DISPLAY 0.680851 (-2060 3310);
PAINT MONO (-2060 3310);
FORCEPROP 0 LASTPIN (-2050 3350) $PN 206
J 2
(-2060 3360);
DISPLAY 0.680851 (-2060 3360);
PAINT MONO (-2060 3360);
FORCEPROP 0 LASTPIN (-2050 3400) $PN 208
J 2
(-2060 3410);
DISPLAY 0.680851 (-2060 3410);
PAINT MONO (-2060 3410);
FORCEPROP 0 LASTPIN (-2050 3450) $PN 210
J 2
(-2060 3460);
DISPLAY 0.680851 (-2060 3460);
PAINT MONO (-2060 3460);
FORCEPROP 0 LASTPIN (-2050 3500) $PN 212
J 2
(-2060 3510);
DISPLAY 0.680851 (-2060 3510);
PAINT MONO (-2060 3510);
FORCEPROP 0 LASTPIN (-2050 3550) $PN 214
J 2
(-2060 3560);
DISPLAY 0.680851 (-2060 3560);
PAINT MONO (-2060 3560);
FORCEPROP 0 LASTPIN (-2050 3600) $PN 216
J 2
(-2060 3610);
DISPLAY 0.680851 (-2060 3610);
PAINT MONO (-2060 3610);
FORCEPROP 0 LASTPIN (-2050 3650) $PN 219
J 2
(-2060 3660);
DISPLAY 0.680851 (-2060 3660);
PAINT MONO (-2060 3660);
FORCEPROP 0 LASTPIN (-2050 3700) $PN 222
J 2
(-2060 3710);
DISPLAY 0.680851 (-2060 3710);
PAINT MONO (-2060 3710);
FORCEPROP 0 LASTPIN (-2050 3750) $PN 224
J 2
(-2060 3760);
DISPLAY 0.680851 (-2060 3760);
PAINT MONO (-2060 3760);
FORCEPROP 0 LASTPIN (-2050 3800) $PN 226
J 2
(-2060 3810);
DISPLAY 0.680851 (-2060 3810);
PAINT MONO (-2060 3810);
FORCEPROP 0 LASTPIN (-2050 3850) $PN 228
J 2
(-2060 3860);
DISPLAY 0.680851 (-2060 3860);
PAINT MONO (-2060 3860);
FORCEPROP 0 LASTPIN (-2050 3900) $PN 230
J 2
(-2060 3910);
DISPLAY 0.680851 (-2060 3910);
PAINT MONO (-2060 3910);
FORCEPROP 0 LASTPIN (-2050 3950) $PN 233
J 2
(-2060 3960);
DISPLAY 0.680851 (-2060 3960);
PAINT MONO (-2060 3960);
FORCEPROP 0 LASTPIN (-2050 4000) $PN 235
J 2
(-2060 4010);
DISPLAY 0.680851 (-2060 4010);
PAINT MONO (-2060 4010);
FORCEPROP 0 LASTPIN (-2050 4050) $PN 237
J 2
(-2060 4060);
DISPLAY 0.680851 (-2060 4060);
PAINT MONO (-2060 4060);
FORCEPROP 0 LASTPIN (-2050 4100) $PN 240
J 2
(-2060 4110);
DISPLAY 0.680851 (-2060 4110);
PAINT MONO (-2060 4110);
FORCEPROP 0 LASTPIN (-2050 4150) $PN 242
J 2
(-2060 4160);
DISPLAY 0.680851 (-2060 4160);
PAINT MONO (-2060 4160);
FORCEPROP 0 LASTPIN (-2050 4200) $PN 244
J 2
(-2060 4210);
DISPLAY 0.680851 (-2060 4210);
PAINT MONO (-2060 4210);
FORCEPROP 0 LASTPIN (-2050 4250) $PN 246
J 2
(-2060 4260);
DISPLAY 0.680851 (-2060 4260);
PAINT MONO (-2060 4260);
FORCEPROP 0 LASTPIN (-2050 4300) $PN 248
J 2
(-2060 4310);
DISPLAY 0.680851 (-2060 4310);
PAINT MONO (-2060 4310);
FORCEPROP 0 LASTPIN (-2050 4350) $PN 251
J 2
(-2060 4360);
DISPLAY 0.680851 (-2060 4360);
PAINT MONO (-2060 4360);
FORCEPROP 0 LASTPIN (-2050 4400) $PN 253
J 2
(-2060 4410);
DISPLAY 0.680851 (-2060 4410);
PAINT MONO (-2060 4410);
FORCEPROP 0 LASTPIN (-2050 4450) $PN 255
J 2
(-2060 4460);
DISPLAY 0.680851 (-2060 4460);
PAINT MONO (-2060 4460);
FORCEPROP 0 LASTPIN (-2050 4500) $PN 257
J 2
(-2060 4510);
DISPLAY 0.680851 (-2060 4510);
PAINT MONO (-2060 4510);
FORCEPROP 0 LASTPIN (-2050 4550) $PN 259
J 2
(-2060 4560);
DISPLAY 0.680851 (-2060 4560);
PAINT MONO (-2060 4560);
FORCEPROP 0 LASTPIN (-2050 4600) $PN 262
J 2
(-2060 4610);
DISPLAY 0.680851 (-2060 4610);
PAINT MONO (-2060 4610);
FORCEPROP 0 LASTPIN (-2050 4650) $PN 264
J 2
(-2060 4660);
DISPLAY 0.680851 (-2060 4660);
PAINT MONO (-2060 4660);
FORCEPROP 0 LASTPIN (-2050 4700) $PN 266
J 2
(-2060 4710);
DISPLAY 0.680851 (-2060 4710);
PAINT MONO (-2060 4710);
FORCEPROP 0 LASTPIN (-2050 4750) $PN 268
J 2
(-2060 4760);
DISPLAY 0.680851 (-2060 4760);
PAINT MONO (-2060 4760);
FORCEPROP 0 LASTPIN (-2050 4800) $PN 270
J 2
(-2060 4810);
DISPLAY 0.680851 (-2060 4810);
PAINT MONO (-2060 4810);
FORCEPROP 0 LASTPIN (-2050 4850) $PN 273
J 2
(-2060 4860);
DISPLAY 0.680851 (-2060 4860);
PAINT MONO (-2060 4860);
FORCEPROP 0 LASTPIN (-2050 4900) $PN 275
J 2
(-2060 4910);
DISPLAY 0.680851 (-2060 4910);
PAINT MONO (-2060 4910);
FORCEPROP 0 LASTPIN (-2050 4950) $PN 277
J 2
(-2060 4960);
DISPLAY 0.680851 (-2060 4960);
PAINT MONO (-2060 4960);
FORCEPROP 0 LASTPIN (-2050 5000) $PN 279
J 2
(-2060 5010);
DISPLAY 0.680851 (-2060 5010);
PAINT MONO (-2060 5010);
FORCEPROP 0 LASTPIN (-2050 5050) $PN 281
J 2
(-2060 5060);
DISPLAY 0.680851 (-2060 5060);
PAINT MONO (-2060 5060);
FORCEPROP 0 LASTPIN (-2050 5100) $PN 284
J 2
(-2060 5110);
DISPLAY 0.680851 (-2060 5110);
PAINT MONO (-2060 5110);
FORCEPROP 0 LASTPIN (-2050 5150) $PN 286
J 2
(-2060 5160);
DISPLAY 0.680851 (-2060 5160);
PAINT MONO (-2060 5160);
FORCEPROP 0 LASTPIN (-2050 5200) $PN 288
J 2
(-2060 5210);
DISPLAY 0.680851 (-2060 5210);
PAINT MONO (-2060 5210);
FORCEPROP 2 LAST PART_TYPE SMLF
J 0
(-1900 5775);
DISPLAY 0.680851 (-1900 5775);
FORCEPROP 1 LAST MATERIAL IO
J 0
(-1900 5525);
DISPLAY 0.468085 (-1900 5525);
PAINT SKYBLUE (-1900 5525);
FORCEPROP 1 LAST PART_NUMBER DFHST8FS479
J 0
(-1900 5600);
DISPLAY 0.468085 (-1900 5600);
PAINT SKYBLUE (-1900 5600);
FORCEPROP 2 LAST VALUE SCONN288_DDR506112002KQ
J 0
(-1900 5725);
DISPLAY 0.446809 (-1900 5725);
PAINT SKYBLUE (-1900 5725);
FORCEPROP 1 LAST NEEDS_NO_SIZE TRUE
J 0
(-1450 3700);
DISPLAY 0.723404 (-1450 3700);
PAINT GREEN (-1450 3700);
DISPLAY INVISIBLE (-1450 3700);
FORCEPROP 1 LAST CDS_LMAN_SYM_OUTLINE -450,1800,450,-1750
J 0
(-1450 3700);
DISPLAY 0.468085 (-1450 3700);
PAINT GREEN (-1450 3700);
DISPLAY INVISIBLE (-1450 3700);
FORCEPROP 1 LAST PATH I538
J 0
(-1450 3700);
DISPLAY 0.723404 (-1450 3700);
PAINT GREEN (-1450 3700);
DISPLAY INVISIBLE (-1450 3700);
FORCEPROP 2 LAST CDS_LIB pure_quanta
J 0
(-1450 3700);
DISPLAY INVISIBLE (-1450 3700);
FORCEADD Q_RES..1
(-7800 2725);
FORCEPROP 1 LAST $LOCATION R1568
J 0
(-7850 2750);
DISPLAY 0.510638 (-7850 2750);
PAINT SKYBLUE (-7850 2750);
FORCEPROP 0 LAST CDS_LOCATION R1568
J 0
(-7850 2800);
DISPLAY 0.680851 (-7850 2800);
DISPLAY INVISIBLE (-7850 2800);
FORCEPROP 0 LAST $SEC 1
J 0
(-7850 2800);
DISPLAY 0.680851 (-7850 2800);
PAINT MONO (-7850 2800);
DISPLAY INVISIBLE (-7850 2800);
FORCEPROP 0 LAST CDS_SEC 1
J 0
(-7850 2800);
DISPLAY 0.680851 (-7850 2800);
DISPLAY INVISIBLE (-7850 2800);
FORCEPROP 1 LASTPIN (-7900 2725) $PN 1
J 0
(-7888 2737);
DISPLAY 0.787234 (-7888 2737);
PAINT MONO (-7888 2737);
FORCEPROP 1 LASTPIN (-7700 2725) $PN 2
J 0
(-7738 2737);
DISPLAY 0.787234 (-7738 2737);
PAINT MONO (-7738 2737);
FORCEPROP 1 LAST VALUE 49.9
J 2
(-7675 2800);
DISPLAY 0.510638 (-7675 2800);
PAINT SKYBLUE (-7675 2800);
FORCEPROP 1 LAST PART_NUMBER CS04992FB07
J 0
(-7850 2825);
DISPLAY 0.978723 (-7850 2825);
DISPLAY INVISIBLE (-7850 2825);
FORCEPROP 1 LAST TOLERANCE 1%
J 0
(-7800 2625);
DISPLAY 0.978723 (-7800 2625);
DISPLAY INVISIBLE (-7800 2625);
FORCEPROP 1 LAST WATTAGE 1/16W
J 2
(-7825 2575);
DISPLAY 0.978723 (-7825 2575);
DISPLAY INVISIBLE (-7825 2575);
FORCEPROP 1 LAST PACK_TYPE 0402LF
J 0
(-7550 2575);
DISPLAY 0.978723 (-7550 2575);
DISPLAY INVISIBLE (-7550 2575);
FORCEPROP 1 LAST MATERIAL CHIP
J 0
(-7800 2575);
DISPLAY 0.978723 (-7800 2575);
DISPLAY INVISIBLE (-7800 2575);
FORCEPROP 2 LAST CDS_LIB pure_quanta
J 0
(-7800 2725);
DISPLAY INVISIBLE (-7800 2725);
FORCEPROP 1 LAST PATH I539
J 0
(-7850 2875);
DISPLAY 0.978723 (-7850 2875);
PAINT WHITE (-7850 2875);
DISPLAY INVISIBLE (-7850 2875);
FORCEADD DNS..2
(-8425 2400);
PAINT RED (-8425 2400);
FORCEPROP 2 LAST CDS_LIB mstr_misc
J 0
(-8425 2400);
DISPLAY INVISIBLE (-8425 2400);
FORCEPROP 1 LAST COMMENT_BODY TRUE
R 1
J 0
(-8350 2175);
DISPLAY 0.872340 (-8350 2175);
PAINT PEACH (-8350 2175);
DISPLAY INVISIBLE (-8350 2175);
FORCEADD QUANTA_TITLE_BLOCK_C..1
(-100 100);
FORCEPROP 0 LAST CDS_CON_LAST_MODIFIED Fri Mar 11 14:52:52 2022
J 0
(-1985 115);
DISPLAY INVISIBLE (-1985 115);
FORCEPROP 1 LAST CUSTOM_TXT_CDS <CON_LAST_MODIFIED>
J 0
(-1985 115);
DISPLAY 0.978723 (-1985 115);
FORCEPROP 2 LAST CUSTOM_TXT_CDS <XR_PAGE_TITLE>
J 0
(-7990 5350);
DISPLAY 0.638298 (-7990 5350);
PAINT PINK (-7990 5350);
DISPLAY INVISIBLE (-7990 5350);
FORCEPROP 1 LAST CUSTOM_TXT_CDS <NAME_2>
J 0
(-3275 150);
FORCEPROP 1 LAST CUSTOM_TXT_CDS <NAME_1>
J 0
(-3275 275);
FORCEPROP 1 LAST CUSTOM_TXT_CDS <Q_NUMBER>
J 0
(-1503 203);
DISPLAY 1.212766 (-1503 203);
FORCEPROP 1 LAST CUSTOM_TXT_CDS <Q_PROJ>
J 0
(-2482 202);
DISPLAY 1.212766 (-2482 202);
FORCEPROP 1 LAST CUSTOM_TXT_CDS <Q_REV>
J 0
(-284 203);
DISPLAY 1.212766 (-284 203);
FORCEPROP 1 LAST CUSTOM_TXT_CDS <CON_PAGE_NUM> OF <CON_TOTAL_PAGES>
J 0
(-546 118);
DISPLAY 0.978723 (-546 118);
FORCEPROP 1 LAST Q_DEPT BU9
J 1
(-3863 149);
DISPLAY 1.957447 (-3863 149);
PAINT GREEN (-3863 149);
FORCEPROP 1 LAST Q_TITLE DDR5 - CPU0 CHA
J 0
(-9425 150);
DISPLAY 2.446809 (-9425 150);
PAINT GREEN (-9425 150);
FORCEPROP 2 LAST CDS_LIB pure_quanta
J 0
(-100 100);
DISPLAY INVISIBLE (-100 100);
FORCEPROP 1 LAST CDS_LMAN_SYM_OUTLINE -9475,6775,100,-125
J 0
(-100 100);
DISPLAY 0.468085 (-100 100);
PAINT GREEN (-100 100);
DISPLAY INVISIBLE (-100 100);
FORCEPROP 2 LAST PAGE_BORDER TRUE
J 0
(-7990 5350);
DISPLAY 0.638298 (-7990 5350);
PAINT PINK (-7990 5350);
DISPLAY INVISIBLE (-7990 5350);
FORCEPROP 1 LAST COMMENT_BODY TRUE
J 0
(-88 87);
DISPLAY 0.978723 (-88 87);
PAINT GREEN (-88 87);
DISPLAY INVISIBLE (-88 87);
FORCEPROP 2 LAST CDS_XR_PAGE_TITLE CR-85 : @T6G_MB_LIB.T6G(SCH_1):PAGE85
J 0
(-7990 5350);
DISPLAY 0.638298 (-7990 5350);
PAINT PINK (-7990 5350);
DISPLAY INVISIBLE (-7990 5350);
WIRE 17 -1 (-7800 4050)(-7800 4000);
WIRE 17 -1 (-7800 4050)(-7800 4075);
WIRE 17 -1 (-7800 3950)(-7800 4000);
WIRE 17 -1 (-7800 3950)(-7800 3900);
WIRE 17 -1 (-7800 4075)(-8300 4075);
FORCEPROP 2 LAST SIG_NAME M_A_CPU0_SA_CB<7:0>
J 0
(-8300 4085);
DISPLAY 0.489362 (-8300 4085);
WIRE 17 -1 (-7800 4750)(-7800 4800);
WIRE 17 -1 (-7800 4800)(-7800 4850);
WIRE 17 -1 (-7800 4850)(-7800 4900);
WIRE 17 -1 (-7800 4900)(-7800 4950);
WIRE 17 -1 (-7800 4950)(-7800 5000);
WIRE 17 -1 (-7800 5000)(-7800 5050);
WIRE 17 -1 (-7800 5050)(-7800 5075);
WIRE 17 -1 (-7800 5075)(-8300 5075);
FORCEPROP 2 LAST SIG_NAME M_A_CPU0_SB_CA<6:0>
J 0
(-8300 5085);
DISPLAY 0.489362 (-8300 5085);
WIRE 17 -1 (-7800 5200)(-7800 5250);
WIRE 17 -1 (-7800 5150)(-7800 5200);
WIRE 17 -1 (-7800 5250)(-7800 5300);
WIRE 17 -1 (-7800 5300)(-7800 5350);
WIRE 17 -1 (-7800 5350)(-7800 5400);
WIRE 17 -1 (-7800 5400)(-7800 5450);
WIRE 17 -1 (-7800 5450)(-7800 5475);
WIRE 17 -1 (-7800 5475)(-8300 5475);
FORCEPROP 2 LAST SIG_NAME M_A_CPU0_SA_CA<6:0>
J 0
(-8300 5485);
DISPLAY 0.489362 (-8300 5485);
WIRE 17 -1 (-7800 3850)(-7800 3900);
WIRE 17 -1 (-7800 3800)(-7800 3850);
WIRE 17 -1 (-7800 3750)(-7800 3800);
WIRE 17 -1 (-7800 3700)(-7800 3750);
WIRE 17 -1 (-7800 3500)(-7800 3450);
WIRE 17 -1 (-7800 3500)(-7800 3550);
WIRE 17 -1 (-7800 3400)(-7800 3450);
WIRE 17 -1 (-7800 3350)(-7800 3400);
WIRE 17 -1 (-7800 3600)(-7800 3550);
WIRE 17 -1 (-7800 3600)(-7800 3625);
WIRE 17 -1 (-7800 3300)(-7800 3350);
WIRE 17 -1 (-7800 3250)(-7800 3300);
WIRE 17 -1 (-7800 3625)(-8300 3625);
FORCEPROP 2 LAST SIG_NAME M_A_CPU0_SB_CB<7:0>
J 0
(-8300 3635);
DISPLAY 0.489362 (-8300 3635);
WIRE 17 -1 (-6000 5050)(-6000 5000);
WIRE 17 -1 (-6000 5100)(-6000 5050);
WIRE 17 -1 (-6000 5000)(-6000 4950);
WIRE 17 -1 (-6000 4950)(-6000 4900);
WIRE 17 -1 (-6000 5150)(-6000 5100);
WIRE 17 -1 (-6000 5200)(-6000 5150);
WIRE 17 -1 (-6000 4900)(-6000 4850);
WIRE 17 -1 (-6000 4850)(-6000 4800);
WIRE 17 -1 (-6000 5250)(-6000 5200);
WIRE 17 -1 (-6000 5300)(-6000 5250);
WIRE 17 -1 (-6000 4800)(-6000 4750);
WIRE 17 -1 (-6000 4750)(-6000 4700);
WIRE 17 -1 (-6000 5350)(-6000 5300);
WIRE 17 -1 (-6000 5400)(-6000 5350);
WIRE 17 -1 (-6000 4650)(-6000 4700);
WIRE 17 -1 (-6000 4600)(-6000 4650);
WIRE 17 -1 (-6000 5450)(-6000 5400);
WIRE 17 -1 (-6000 5475)(-6000 5450);
WIRE 17 -1 (-6000 4550)(-6000 4600);
WIRE 17 -1 (-6000 4500)(-6000 4550);
WIRE 17 -1 (-6000 5475)(-5550 5475);
FORCEPROP 2 LAST SIG_NAME M_A_CPU0_SA_DQ<31:0>
J 2
(-5550 5485);
DISPLAY 0.489362 (-5550 5485);
WIRE 17 -1 (-6000 4500)(-6000 4450);
WIRE 17 -1 (-6000 4450)(-6000 4400);
WIRE 17 -1 (-6000 4400)(-6000 4350);
WIRE 17 -1 (-6000 4350)(-6000 4300);
WIRE 17 -1 (-6000 4300)(-6000 4250);
WIRE 17 -1 (-6000 4250)(-6000 4200);
WIRE 17 -1 (-6000 4200)(-6000 4150);
WIRE 17 -1 (-6000 4150)(-6000 4100);
WIRE 17 -1 (-6000 4050)(-6000 4100);
WIRE 17 -1 (-6000 4000)(-6000 4050);
WIRE 17 -1 (-6000 3950)(-6000 4000);
WIRE 17 -1 (-6000 3900)(-6000 3950);
WIRE 17 -1 (-6000 3800)(-6000 3750);
WIRE 17 -1 (-6000 3825)(-6000 3800);
WIRE 17 -1 (-6000 3750)(-6000 3700);
WIRE 17 -1 (-6000 3700)(-6000 3650);
WIRE 17 -1 (-6000 3825)(-5550 3825);
FORCEPROP 2 LAST SIG_NAME M_A_CPU0_SB_DQ<31:0>
J 2
(-5550 3835);
DISPLAY 0.489362 (-5550 3835);
WIRE 17 -1 (-6000 3650)(-6000 3600);
WIRE 17 -1 (-6000 3600)(-6000 3550);
WIRE 17 -1 (-6000 3550)(-6000 3500);
WIRE 17 -1 (-6000 3500)(-6000 3450);
WIRE 17 -1 (-6000 3450)(-6000 3400);
WIRE 17 -1 (-6000 3400)(-6000 3350);
WIRE 17 -1 (-6000 3350)(-6000 3300);
WIRE 17 -1 (-6000 3300)(-6000 3250);
WIRE 17 -1 (-6000 3250)(-6000 3200);
WIRE 17 -1 (-6000 3200)(-6000 3150);
WIRE 17 -1 (-6000 3150)(-6000 3100);
WIRE 17 -1 (-6000 3100)(-6000 3050);
WIRE 17 -1 (-6000 3000)(-6000 3050);
WIRE 17 -1 (-6000 2950)(-6000 3000);
WIRE 17 -1 (-6000 2900)(-6000 2950);
WIRE 17 -1 (-6000 2850)(-6000 2900);
WIRE 17 -1 (-6000 2850)(-6000 2800);
WIRE 17 -1 (-6000 2800)(-6000 2750);
WIRE 17 -1 (-6000 2750)(-6000 2700);
WIRE 17 -1 (-6000 2700)(-6000 2650);
WIRE 17 -1 (-6000 2650)(-6000 2600);
WIRE 17 -1 (-6000 2600)(-6000 2550);
WIRE 17 -1 (-6000 2550)(-6000 2500);
WIRE 17 -1 (-6000 2500)(-6000 2450);
WIRE 17 -1 (-6000 2400)(-6000 2450);
WIRE 17 -1 (-6000 2350)(-6000 2400);
WIRE 17 -1 (-6000 2300)(-6000 2350);
WIRE 17 -1 (-6000 2250)(-6000 2300);
WIRE 17 -1 (-3550 4600)(-3550 4500);
WIRE 17 -1 (-3550 4700)(-3550 4600);
WIRE 17 -1 (-3550 4700)(-3550 4800);
WIRE 17 -1 (-3550 4800)(-3550 4900);
WIRE 17 -1 (-3550 4900)(-3550 5000);
WIRE 17 -1 (-3550 5100)(-3550 5000);
WIRE 17 -1 (-3550 5200)(-3550 5100);
WIRE 17 -1 (-3550 5300)(-3550 5200);
WIRE 17 -1 (-3550 5400)(-3550 5300);
WIRE 17 -1 (-3550 5425)(-3550 5400);
WIRE 17 -1 (-3550 5425)(-2850 5425);
FORCEPROP 2 LAST SIG_NAME M_A_CPU0_SA_DQS_DP<9:0>
J 0
(-3385 5435);
DISPLAY 0.489362 (-3385 5435);
WIRE 17 -1 (-3350 3500)(-3350 3400);
WIRE 17 -1 (-3350 3600)(-3350 3500);
WIRE 17 -1 (-3350 3600)(-3350 3700);
WIRE 17 -1 (-3350 3700)(-3350 3800);
WIRE 17 -1 (-3350 3800)(-3350 3900);
WIRE 17 -1 (-3350 4000)(-3350 3900);
WIRE 17 -1 (-3350 4100)(-3350 4000);
WIRE 17 -1 (-3350 4200)(-3350 4100);
WIRE 17 -1 (-3350 4300)(-3350 4200);
WIRE 17 -1 (-3350 4325)(-3350 4300);
WIRE 17 -1 (-3350 4325)(-2850 4325);
FORCEPROP 2 LAST SIG_NAME M_A_CPU0_SB_DQS_DN<9:0>
J 2
(-2850 4335);
DISPLAY 0.489362 (-2850 4335);
WIRE 17 -1 (-3550 3550)(-3550 3450);
WIRE 17 -1 (-3550 3650)(-3550 3550);
WIRE 17 -1 (-3550 3650)(-3550 3750);
WIRE 17 -1 (-3550 3750)(-3550 3850);
WIRE 17 -1 (-3550 3850)(-3550 3950);
WIRE 17 -1 (-3550 4050)(-3550 3950);
WIRE 17 -1 (-3550 4150)(-3550 4050);
WIRE 17 -1 (-3550 4250)(-3550 4150);
WIRE 17 -1 (-3550 4350)(-3550 4250);
WIRE 17 -1 (-3550 4375)(-3550 4350);
WIRE 17 -1 (-3550 4375)(-2850 4375);
FORCEPROP 2 LAST SIG_NAME M_A_CPU0_SB_DQS_DP<9:0>
J 2
(-2850 4385);
DISPLAY 0.489362 (-2850 4385);
WIRE 17 -1 (-3350 4650)(-3350 4550);
WIRE 17 -1 (-3350 4650)(-3350 4750);
WIRE 17 -1 (-3350 4550)(-3350 4450);
WIRE 17 -1 (-3350 4750)(-3350 4850);
WIRE 17 -1 (-3350 4850)(-3350 4950);
WIRE 17 -1 (-3350 5050)(-3350 4950);
WIRE 17 -1 (-3350 5150)(-3350 5050);
WIRE 17 -1 (-3350 5250)(-3350 5150);
WIRE 17 -1 (-3350 5350)(-3350 5250);
WIRE 17 -1 (-3350 5375)(-3350 5350);
WIRE 17 -1 (-3350 5375)(-2850 5375);
FORCEPROP 2 LAST SIG_NAME M_A_CPU0_SA_DQS_DN<9:0>
J 0
(-3385 5385);
DISPLAY 0.489362 (-3385 5385);
WIRE 16 -1 (-6500 1150)(-6500 1225);
WIRE 16 -1 (-9000 3050)(-9000 3125);
WIRE 16 -1 (-8700 2500)(-8700 2525);
WIRE 16 -1 (-8450 2500)(-8450 2525);
WIRE 16 -1 (-7500 2375)(-8150 2375);
FORCEPROP 2 LAST SIG_NAME TP_CHA_CPU0_DIMM0_RFU_4
J 0
(-8150 2385);
DISPLAY 0.489362 (-8150 2385);
FORCEPROP 2 LASTPROP $XRERR UNIQUE?
J 0
(-8390 2375);
DISPLAY 0.638298 (-8390 2375);
PAINT MONO (-8390 2375);
DISPLAY INVISIBLE (-8390 2375);
WIRE 16 -1 (-7500 2425)(-8150 2425);
FORCEPROP 2 LAST SIG_NAME TP_CHA_CPU0_DIMM0_RFU_5
J 0
(-8150 2435);
DISPLAY 0.489362 (-8150 2435);
FORCEPROP 2 LASTPROP $XRERR UNIQUE?
J 0
(-8390 2425);
DISPLAY 0.638298 (-8390 2425);
PAINT MONO (-8390 2425);
DISPLAY INVISIBLE (-8390 2425);
WIRE 16 -1 (-7500 2475)(-8150 2475);
FORCEPROP 2 LAST SIG_NAME TP_CHA_CPU0_DIMM0_RFU_6
J 0
(-8150 2485);
DISPLAY 0.489362 (-8150 2485);
FORCEPROP 2 LASTPROP $XRERR UNIQUE?
J 0
(-8390 2475);
DISPLAY 0.638298 (-8390 2475);
PAINT MONO (-8390 2475);
DISPLAY INVISIBLE (-8390 2475);
WIRE 16 -1 (-8450 2300)(-8450 2250);
WIRE 16 -1 (-8250 2250)(-8450 2250);
WIRE 16 -1 (-8450 2250)(-8475 2250);
WIRE 16 -1 (-8250 2250)(-8250 2575);
WIRE 16 -1 (-8250 2575)(-7500 2575);
FORCEPROP 2 LAST SIG_NAME PWRGD_CHA_CPU0_DIMM0
J 0
(-8160 2585);
DISPLAY 0.489362 (-8160 2585);
FORCEPROP 2 LASTPROP $XRERR UNIQUE?
J 0
(-8400 2585);
DISPLAY 0.638298 (-8400 2585);
PAINT MONO (-8400 2585);
DISPLAY INVISIBLE (-8400 2585);
WIRE 16 -1 (-7900 2725)(-8325 2725);
WIRE 16 -1 (-8875 2975)(-7500 2975);
WIRE 16 -1 (-8875 3400)(-8875 2975);
WIRE 16 -1 (-8875 3475)(-8875 3400);
WIRE 16 -1 (-9000 3400)(-8875 3400);
WIRE 16 -1 (-9000 3325)(-9000 3400);
WIRE 16 -1 (-650 2050)(-650 2000);
WIRE 16 -1 (-650 2100)(-650 2050);
WIRE 16 -1 (-650 2050)(-850 2050);
WIRE 16 -1 (-650 2000)(-650 1800);
WIRE 16 -1 (-650 2000)(-850 2000);
WIRE 16 -1 (-650 2200)(-650 2100);
WIRE 16 -1 (-650 2100)(-850 2100);
WIRE 16 -1 (-650 2250)(-650 2200);
WIRE 16 -1 (-650 2200)(-850 2200);
WIRE 16 -1 (-650 2300)(-650 2250);
WIRE 16 -1 (-650 2250)(-850 2250);
WIRE 16 -1 (-650 2350)(-650 2300);
WIRE 16 -1 (-650 2300)(-850 2300);
WIRE 16 -1 (-650 2400)(-650 2350);
WIRE 16 -1 (-650 2350)(-850 2350);
WIRE 16 -1 (-650 2450)(-650 2400);
WIRE 16 -1 (-650 2400)(-850 2400);
WIRE 16 -1 (-650 2500)(-650 2450);
WIRE 16 -1 (-650 2450)(-850 2450);
WIRE 16 -1 (-650 2550)(-650 2500);
WIRE 16 -1 (-650 2500)(-850 2500);
WIRE 16 -1 (-650 2600)(-650 2550);
WIRE 16 -1 (-650 2550)(-850 2550);
WIRE 16 -1 (-650 2650)(-650 2600);
WIRE 16 -1 (-650 2600)(-850 2600);
WIRE 16 -1 (-650 2700)(-650 2650);
WIRE 16 -1 (-650 2650)(-850 2650);
WIRE 16 -1 (-650 2750)(-650 2700);
WIRE 16 -1 (-650 2700)(-850 2700);
WIRE 16 -1 (-650 2800)(-650 2750);
WIRE 16 -1 (-650 2750)(-850 2750);
WIRE 16 -1 (-650 2850)(-650 2800);
WIRE 16 -1 (-650 2800)(-850 2800);
WIRE 16 -1 (-650 2900)(-650 2850);
WIRE 16 -1 (-650 2850)(-850 2850);
WIRE 16 -1 (-650 2950)(-650 2900);
WIRE 16 -1 (-650 2900)(-850 2900);
WIRE 16 -1 (-650 3000)(-650 2950);
WIRE 16 -1 (-650 2950)(-850 2950);
WIRE 16 -1 (-650 3050)(-650 3000);
WIRE 16 -1 (-650 3000)(-850 3000);
WIRE 16 -1 (-650 3100)(-650 3050);
WIRE 16 -1 (-650 3050)(-850 3050);
WIRE 16 -1 (-650 3150)(-650 3100);
WIRE 16 -1 (-650 3100)(-850 3100);
WIRE 16 -1 (-650 3200)(-650 3150);
WIRE 16 -1 (-650 3150)(-850 3150);
WIRE 16 -1 (-650 3250)(-650 3200);
WIRE 16 -1 (-650 3200)(-850 3200);
WIRE 16 -1 (-650 3300)(-650 3250);
WIRE 16 -1 (-650 3250)(-850 3250);
WIRE 16 -1 (-650 3350)(-650 3300);
WIRE 16 -1 (-650 3300)(-850 3300);
WIRE 16 -1 (-650 3400)(-650 3350);
WIRE 16 -1 (-650 3350)(-850 3350);
WIRE 16 -1 (-650 3450)(-650 3400);
WIRE 16 -1 (-650 3400)(-850 3400);
WIRE 16 -1 (-650 3500)(-650 3450);
WIRE 16 -1 (-650 3450)(-850 3450);
WIRE 16 -1 (-650 3550)(-650 3500);
WIRE 16 -1 (-650 3500)(-850 3500);
WIRE 16 -1 (-650 3600)(-650 3550);
WIRE 16 -1 (-650 3550)(-850 3550);
WIRE 16 -1 (-650 3650)(-650 3600);
WIRE 16 -1 (-650 3600)(-850 3600);
WIRE 16 -1 (-650 3700)(-650 3650);
WIRE 16 -1 (-650 3650)(-850 3650);
WIRE 16 -1 (-650 3750)(-650 3700);
WIRE 16 -1 (-650 3700)(-850 3700);
WIRE 16 -1 (-650 3800)(-650 3750);
WIRE 16 -1 (-650 3750)(-850 3750);
WIRE 16 -1 (-650 3850)(-650 3800);
WIRE 16 -1 (-650 3800)(-850 3800);
WIRE 16 -1 (-650 3900)(-650 3850);
WIRE 16 -1 (-650 3850)(-850 3850);
WIRE 16 -1 (-650 3950)(-650 3900);
WIRE 16 -1 (-650 3900)(-850 3900);
WIRE 16 -1 (-650 4000)(-650 3950);
WIRE 16 -1 (-650 3950)(-850 3950);
WIRE 16 -1 (-650 4050)(-650 4000);
WIRE 16 -1 (-650 4000)(-850 4000);
WIRE 16 -1 (-650 4100)(-650 4050);
WIRE 16 -1 (-650 4050)(-850 4050);
WIRE 16 -1 (-650 4150)(-650 4100);
WIRE 16 -1 (-650 4100)(-850 4100);
WIRE 16 -1 (-650 4200)(-650 4150);
WIRE 16 -1 (-650 4150)(-850 4150);
WIRE 16 -1 (-650 4250)(-650 4200);
WIRE 16 -1 (-650 4200)(-850 4200);
WIRE 16 -1 (-650 4300)(-650 4250);
WIRE 16 -1 (-650 4250)(-850 4250);
WIRE 16 -1 (-650 4350)(-650 4300);
WIRE 16 -1 (-650 4300)(-850 4300);
WIRE 16 -1 (-650 4400)(-650 4350);
WIRE 16 -1 (-650 4350)(-850 4350);
WIRE 16 -1 (-650 4450)(-650 4400);
WIRE 16 -1 (-650 4400)(-850 4400);
WIRE 16 -1 (-650 4500)(-650 4450);
WIRE 16 -1 (-650 4450)(-850 4450);
WIRE 16 -1 (-650 4550)(-650 4500);
WIRE 16 -1 (-650 4500)(-850 4500);
WIRE 16 -1 (-650 4600)(-650 4550);
WIRE 16 -1 (-650 4550)(-850 4550);
WIRE 16 -1 (-650 4650)(-650 4600);
WIRE 16 -1 (-650 4600)(-850 4600);
WIRE 16 -1 (-650 4700)(-650 4650);
WIRE 16 -1 (-650 4650)(-850 4650);
WIRE 16 -1 (-650 4750)(-650 4700);
WIRE 16 -1 (-650 4700)(-850 4700);
WIRE 16 -1 (-650 4800)(-650 4750);
WIRE 16 -1 (-650 4750)(-850 4750);
WIRE 16 -1 (-650 4850)(-650 4800);
WIRE 16 -1 (-650 4800)(-850 4800);
WIRE 16 -1 (-650 4900)(-650 4850);
WIRE 16 -1 (-650 4850)(-850 4850);
WIRE 16 -1 (-650 4950)(-650 4900);
WIRE 16 -1 (-650 4900)(-850 4900);
WIRE 16 -1 (-650 5000)(-650 4950);
WIRE 16 -1 (-650 4950)(-850 4950);
WIRE 16 -1 (-650 5050)(-650 5000);
WIRE 16 -1 (-650 5000)(-850 5000);
WIRE 16 -1 (-650 5100)(-650 5050);
WIRE 16 -1 (-650 5050)(-850 5050);
WIRE 16 -1 (-650 5150)(-650 5100);
WIRE 16 -1 (-650 5100)(-850 5100);
WIRE 16 -1 (-650 5200)(-650 5150);
WIRE 16 -1 (-650 5150)(-850 5150);
WIRE 16 -1 (-650 5250)(-650 5200);
WIRE 16 -1 (-650 5200)(-850 5200);
WIRE 16 -1 (-650 5300)(-650 5250);
WIRE 16 -1 (-650 5250)(-850 5250);
WIRE 16 -1 (-650 5350)(-650 5300);
WIRE 16 -1 (-650 5300)(-850 5300);
WIRE 16 -1 (-650 5350)(-850 5350);
WIRE 16 -1 (-2050 2100)(-2250 2100);
WIRE 16 -1 (-2250 2150)(-2250 2100);
WIRE 16 -1 (-2250 2100)(-2250 2000);
WIRE 16 -1 (-2050 2150)(-2250 2150);
WIRE 16 -1 (-2250 2200)(-2250 2150);
WIRE 16 -1 (-2050 2200)(-2250 2200);
WIRE 16 -1 (-2250 2250)(-2250 2200);
WIRE 16 -1 (-2050 2250)(-2250 2250);
WIRE 16 -1 (-2250 2300)(-2250 2250);
WIRE 16 -1 (-2250 2350)(-2250 2300);
WIRE 16 -1 (-2050 2300)(-2250 2300);
WIRE 16 -1 (-2050 2350)(-2250 2350);
WIRE 16 -1 (-2250 2400)(-2250 2350);
WIRE 16 -1 (-2050 2400)(-2250 2400);
WIRE 16 -1 (-2250 2450)(-2250 2400);
WIRE 16 -1 (-2050 2450)(-2250 2450);
WIRE 16 -1 (-2250 2500)(-2250 2450);
WIRE 16 -1 (-2050 2500)(-2250 2500);
WIRE 16 -1 (-2250 2550)(-2250 2500);
WIRE 16 -1 (-2250 2600)(-2250 2550);
WIRE 16 -1 (-2050 2550)(-2250 2550);
WIRE 16 -1 (-2050 2600)(-2250 2600);
WIRE 16 -1 (-2250 2650)(-2250 2600);
WIRE 16 -1 (-2050 2650)(-2250 2650);
WIRE 16 -1 (-2250 2700)(-2250 2650);
WIRE 16 -1 (-2050 2700)(-2250 2700);
WIRE 16 -1 (-2250 2750)(-2250 2700);
WIRE 16 -1 (-2050 2750)(-2250 2750);
WIRE 16 -1 (-2250 2800)(-2250 2750);
WIRE 16 -1 (-2250 2850)(-2250 2800);
WIRE 16 -1 (-2050 2800)(-2250 2800);
WIRE 16 -1 (-2050 2850)(-2250 2850);
WIRE 16 -1 (-2250 2900)(-2250 2850);
WIRE 16 -1 (-2050 2900)(-2250 2900);
WIRE 16 -1 (-2250 2950)(-2250 2900);
WIRE 16 -1 (-2050 2950)(-2250 2950);
WIRE 16 -1 (-2250 3000)(-2250 2950);
WIRE 16 -1 (-2050 3000)(-2250 3000);
WIRE 16 -1 (-2250 3050)(-2250 3000);
WIRE 16 -1 (-2250 3100)(-2250 3050);
WIRE 16 -1 (-2050 3050)(-2250 3050);
WIRE 16 -1 (-2050 3100)(-2250 3100);
WIRE 16 -1 (-2250 3150)(-2250 3100);
WIRE 16 -1 (-2050 3150)(-2250 3150);
WIRE 16 -1 (-2250 3200)(-2250 3150);
WIRE 16 -1 (-2050 3200)(-2250 3200);
WIRE 16 -1 (-2250 3250)(-2250 3200);
WIRE 16 -1 (-2050 3250)(-2250 3250);
WIRE 16 -1 (-2250 3300)(-2250 3250);
WIRE 16 -1 (-2250 3350)(-2250 3300);
WIRE 16 -1 (-2050 3300)(-2250 3300);
WIRE 16 -1 (-2050 3350)(-2250 3350);
WIRE 16 -1 (-2250 3400)(-2250 3350);
WIRE 16 -1 (-2050 3400)(-2250 3400);
WIRE 16 -1 (-2250 3450)(-2250 3400);
WIRE 16 -1 (-2050 3450)(-2250 3450);
WIRE 16 -1 (-2250 3500)(-2250 3450);
WIRE 16 -1 (-2050 3500)(-2250 3500);
WIRE 16 -1 (-2250 3550)(-2250 3500);
WIRE 16 -1 (-2250 3600)(-2250 3550);
WIRE 16 -1 (-2050 3550)(-2250 3550);
WIRE 16 -1 (-2050 3600)(-2250 3600);
WIRE 16 -1 (-2250 3650)(-2250 3600);
WIRE 16 -1 (-2050 3650)(-2250 3650);
WIRE 16 -1 (-2250 3700)(-2250 3650);
WIRE 16 -1 (-2050 3700)(-2250 3700);
WIRE 16 -1 (-2250 3750)(-2250 3700);
WIRE 16 -1 (-2050 3750)(-2250 3750);
WIRE 16 -1 (-2250 3800)(-2250 3750);
WIRE 16 -1 (-2250 3850)(-2250 3800);
WIRE 16 -1 (-2050 3800)(-2250 3800);
WIRE 16 -1 (-2050 3850)(-2250 3850);
WIRE 16 -1 (-2250 3900)(-2250 3850);
WIRE 16 -1 (-2050 3900)(-2250 3900);
WIRE 16 -1 (-2250 3950)(-2250 3900);
WIRE 16 -1 (-2050 3950)(-2250 3950);
WIRE 16 -1 (-2250 4000)(-2250 3950);
WIRE 16 -1 (-2050 4000)(-2250 4000);
WIRE 16 -1 (-2250 4050)(-2250 4000);
WIRE 16 -1 (-2250 4100)(-2250 4050);
WIRE 16 -1 (-2050 4050)(-2250 4050);
WIRE 16 -1 (-2050 4100)(-2250 4100);
WIRE 16 -1 (-2250 4150)(-2250 4100);
WIRE 16 -1 (-2050 4150)(-2250 4150);
WIRE 16 -1 (-2250 4200)(-2250 4150);
WIRE 16 -1 (-2050 4200)(-2250 4200);
WIRE 16 -1 (-2250 4250)(-2250 4200);
WIRE 16 -1 (-2050 4250)(-2250 4250);
WIRE 16 -1 (-2250 4300)(-2250 4250);
WIRE 16 -1 (-2050 4300)(-2250 4300);
WIRE 16 -1 (-2250 4350)(-2250 4300);
WIRE 16 -1 (-2250 4400)(-2250 4350);
WIRE 16 -1 (-2050 4350)(-2250 4350);
WIRE 16 -1 (-2050 4400)(-2250 4400);
WIRE 16 -1 (-2250 4450)(-2250 4400);
WIRE 16 -1 (-2050 4450)(-2250 4450);
WIRE 16 -1 (-2250 4500)(-2250 4450);
WIRE 16 -1 (-2050 4500)(-2250 4500);
WIRE 16 -1 (-2250 4550)(-2250 4500);
WIRE 16 -1 (-2050 4550)(-2250 4550);
WIRE 16 -1 (-2250 4600)(-2250 4550);
WIRE 16 -1 (-2250 4650)(-2250 4600);
WIRE 16 -1 (-2050 4600)(-2250 4600);
WIRE 16 -1 (-2050 4650)(-2250 4650);
WIRE 16 -1 (-2250 4700)(-2250 4650);
WIRE 16 -1 (-2050 4700)(-2250 4700);
WIRE 16 -1 (-2250 4750)(-2250 4700);
WIRE 16 -1 (-2050 4750)(-2250 4750);
WIRE 16 -1 (-2250 4800)(-2250 4750);
WIRE 16 -1 (-2050 4800)(-2250 4800);
WIRE 16 -1 (-2250 4850)(-2250 4800);
WIRE 16 -1 (-2250 4900)(-2250 4850);
WIRE 16 -1 (-2050 4850)(-2250 4850);
WIRE 16 -1 (-2050 4900)(-2250 4900);
WIRE 16 -1 (-2250 4950)(-2250 4900);
WIRE 16 -1 (-2050 4950)(-2250 4950);
WIRE 16 -1 (-2250 5000)(-2250 4950);
WIRE 16 -1 (-2050 5000)(-2250 5000);
WIRE 16 -1 (-2250 5050)(-2250 5000);
WIRE 16 -1 (-2050 5050)(-2250 5050);
WIRE 16 -1 (-2250 5100)(-2250 5050);
WIRE 16 -1 (-2250 5150)(-2250 5100);
WIRE 16 -1 (-2050 5100)(-2250 5100);
WIRE 16 -1 (-2050 5150)(-2250 5150);
WIRE 16 -1 (-2250 5200)(-2250 5150);
WIRE 16 -1 (-2050 5200)(-2250 5200);
WIRE 16 -1 (-2375 5825)(-2950 5825);
WIRE 16 -1 (-2375 5825)(-2375 5950);
WIRE 16 -1 (-2950 5825)(-2950 5950);
WIRE 16 -1 (-2950 5825)(-2950 5750);
WIRE 16 -1 (-2375 6250)(-2950 6250);
WIRE 16 -1 (-2375 6250)(-2250 6250);
WIRE 16 -1 (-2375 6250)(-2375 6150);
WIRE 16 -1 (-2950 6250)(-2950 6325);
WIRE 16 -1 (-2950 6150)(-2950 6250);
WIRE 16 -1 (-2250 6250)(-2250 5350);
WIRE 16 -1 (-2050 5350)(-2250 5350);
WIRE 16 -1 (-2250 5300)(-2250 5350);
WIRE 16 -1 (-2050 5300)(-2250 5300);
WIRE 16 -1 (-2250 5250)(-2250 5300);
WIRE 16 -1 (-2050 5250)(-2250 5250);
WIRE 16 -1 (-7500 2875)(-8300 2875);
FORCEPROP 2 LAST SIG_NAME I3C_SPD_DDRAF_CPU0_SDA
J 0
(-8310 2885);
DISPLAY 0.489362 (-8310 2885);
WIRE 16 -1 (-7500 2275)(-8150 2275);
FORCEPROP 2 LAST SIG_NAME TP_CHA_CPU0_DIMM0_RFU_2
J 0
(-8150 2285);
DISPLAY 0.489362 (-8150 2285);
FORCEPROP 2 LASTPROP $XRERR UNIQUE?
J 0
(-8390 2275);
DISPLAY 0.638298 (-8390 2275);
PAINT MONO (-8390 2275);
DISPLAY INVISIBLE (-8390 2275);
WIRE 16 -1 (-7600 2825)(-7600 2725);
WIRE 16 -1 (-7500 2825)(-7600 2825);
FORCEPROP 2 LAST SIG_NAME I3C_SPD_DDRA_CPU0_SCL
J 0
(-7985 2835);
DISPLAY 0.446809 (-7985 2835);
FORCEPROP 2 LASTPROP $XRERR UNIQUE?
J 0
(-8225 2835);
DISPLAY 0.638298 (-8225 2835);
PAINT MONO (-8225 2835);
DISPLAY INVISIBLE (-8225 2835);
WIRE 16 -1 (-7600 2725)(-7700 2725);
WIRE 16 -1 (-7500 2025)(-8300 2025);
FORCEPROP 2 LAST SIG_NAME M_A_CPU0_SA_RSP<0>
J 0
(-8300 2035);
DISPLAY 0.489362 (-8300 2035);
WIRE 16 -1 (-7500 2175)(-8150 2175);
FORCEPROP 2 LAST SIG_NAME TP_CHA_CPU0_DIMM0_RFU_0
J 0
(-8150 2185);
DISPLAY 0.489362 (-8150 2185);
FORCEPROP 2 LASTPROP $XRERR UNIQUE?
J 0
(-8390 2175);
DISPLAY 0.638298 (-8390 2175);
PAINT MONO (-8390 2175);
DISPLAY INVISIBLE (-8390 2175);
WIRE 16 -1 (-7500 1975)(-8300 1975);
FORCEPROP 2 LAST SIG_NAME M_A_CPU0_SB_RSP<0>
J 0
(-8300 1985);
DISPLAY 0.489362 (-8300 1985);
WIRE 16 -1 (-7500 2325)(-8150 2325);
FORCEPROP 2 LAST SIG_NAME TP_CHA_CPU0_DIMM0_RFU_3
J 0
(-8150 2335);
DISPLAY 0.489362 (-8150 2335);
FORCEPROP 2 LASTPROP $XRERR UNIQUE?
J 0
(-8390 2325);
DISPLAY 0.638298 (-8390 2325);
PAINT MONO (-8390 2325);
DISPLAY INVISIBLE (-8390 2325);
WIRE 16 -1 (-7500 3275)(-7700 3275);
WIRE 16 -1 (-7500 2925)(-8300 2925);
FORCEPROP 2 LAST SIG_NAME PD_CHA_CPU0_DIMM0_SAA
J 0
(-8300 2935);
DISPLAY 0.489362 (-8300 2935);
WIRE 16 -1 (-7500 3075)(-8300 3075);
FORCEPROP 2 LAST SIG_NAME M_A_CPU0_ALERT_N
J 0
(-8285 3085);
DISPLAY 0.489362 (-8285 3085);
WIRE 16 -1 (-7500 3125)(-8300 3125);
FORCEPROP 2 LAST SIG_NAME M_A_CPU0_RESET_N
J 0
(-8285 3135);
DISPLAY 0.489362 (-8285 3135);
WIRE 16 -1 (-8700 2300)(-8700 2250);
WIRE 16 -1 (-8675 2250)(-8700 2250);
WIRE 16 -1 (-8700 2250)(-9025 2250);
FORCEPROP 2 LAST SIG_NAME PWRGD_CHAF_CPU0
J 0
(-9060 2260);
DISPLAY 0.489362 (-9060 2260);
WIRE 16 -1 (-7500 4425)(-8300 4425);
FORCEPROP 2 LAST SIG_NAME M_A_CPU0_SA_CS_N<0>
J 0
(-8300 4435);
DISPLAY 0.489362 (-8300 4435);
WIRE 16 -1 (-7500 4575)(-8300 4575);
FORCEPROP 2 LAST SIG_NAME M_A_CPU0_SB_PAR
J 0
(-8300 4585);
DISPLAY 0.489362 (-8300 4585);
WIRE 16 -1 (-7500 3525)(-7700 3525);
WIRE 16 -1 (-7500 3575)(-7700 3575);
WIRE 16 -1 (-7500 3675)(-7700 3675);
WIRE 16 -1 (-7500 3725)(-7700 3725);
WIRE 16 -1 (-7500 3775)(-7700 3775);
WIRE 16 -1 (-7500 3825)(-7700 3825);
WIRE 16 -1 (-7500 3875)(-7700 3875);
WIRE 16 -1 (-7500 2225)(-8150 2225);
FORCEPROP 2 LAST SIG_NAME TP_CHA_CPU0_DIMM0_RFU_1
J 0
(-8150 2235);
DISPLAY 0.489362 (-8150 2235);
FORCEPROP 2 LASTPROP $XRERR UNIQUE?
J 0
(-8390 2225);
DISPLAY 0.638298 (-8390 2225);
PAINT MONO (-8390 2225);
DISPLAY INVISIBLE (-8390 2225);
WIRE 16 -1 (-3850 4325)(-3650 4325);
WIRE 16 -1 (-3450 5025)(-3850 5025);
WIRE 16 -1 (-3650 5075)(-3850 5075);
WIRE 16 -1 (-3450 5125)(-3850 5125);
WIRE 16 -1 (-6100 4575)(-6300 4575);
WIRE 16 -1 (-6300 4625)(-6100 4625);
WIRE 16 -1 (-6100 4875)(-6300 4875);
WIRE 16 -1 (-6100 5075)(-6300 5075);
WIRE 16 -1 (-6100 5125)(-6300 5125);
WIRE 16 -1 (-6100 5175)(-6300 5175);
WIRE 16 -1 (-6300 5225)(-6100 5225);
WIRE 16 -1 (-6100 5275)(-6300 5275);
WIRE 16 -1 (-6100 5325)(-6300 5325);
WIRE 16 -1 (-3850 4425)(-3450 4425);
WIRE 16 -1 (-3450 4275)(-3850 4275);
WIRE 16 -1 (-3650 4225)(-3850 4225);
WIRE 16 -1 (-3450 4175)(-3850 4175);
WIRE 16 -1 (-3650 4125)(-3850 4125);
WIRE 16 -1 (-3450 4075)(-3850 4075);
WIRE 16 -1 (-3650 4025)(-3850 4025);
WIRE 16 -1 (-3450 3975)(-3850 3975);
WIRE 16 -1 (-3450 3875)(-3850 3875);
WIRE 16 -1 (-3650 3825)(-3850 3825);
WIRE 16 -1 (-3450 3775)(-3850 3775);
WIRE 16 -1 (-6100 2225)(-6300 2225);
WIRE 16 -1 (-6100 4675)(-6300 4675);
WIRE 16 -1 (-7500 4275)(-8300 4275);
FORCEPROP 2 LAST SIG_NAME M_A_CPU0_SB_CS_N<0>
J 0
(-8300 4285);
DISPLAY 0.489362 (-8300 4285);
WIRE 16 -1 (-7500 4475)(-8300 4475);
FORCEPROP 2 LAST SIG_NAME M_A_CPU0_SA_CS_N<1>
J 0
(-8300 4485);
DISPLAY 0.489362 (-8300 4485);
WIRE 16 -1 (-7500 5425)(-7700 5425);
WIRE 16 -1 (-7500 5125)(-7700 5125);
WIRE 16 -1 (-6300 5425)(-6100 5425);
WIRE 16 -1 (-7500 4975)(-7700 4975);
WIRE 16 -1 (-3850 5375)(-3650 5375);
WIRE 16 -1 (-3450 5325)(-3850 5325);
WIRE 16 -1 (-6100 5375)(-6300 5375);
WIRE 16 -1 (-3650 5275)(-3850 5275);
WIRE 16 -1 (-3450 5225)(-3850 5225);
WIRE 16 -1 (-3650 5175)(-3850 5175);
WIRE 16 -1 (-3850 3925)(-3650 3925);
WIRE 16 -1 (-3850 4975)(-3650 4975);
WIRE 16 -1 (-3450 4925)(-3850 4925);
WIRE 16 -1 (-3650 4875)(-3850 4875);
WIRE 16 -1 (-3450 4825)(-3850 4825);
WIRE 16 -1 (-3650 3725)(-3850 3725);
WIRE 16 -1 (-3450 3675)(-3850 3675);
WIRE 16 -1 (-3650 4775)(-3850 4775);
WIRE 16 -1 (-3450 4725)(-3850 4725);
WIRE 16 -1 (-3650 3625)(-3850 3625);
WIRE 16 -1 (-3450 3575)(-3850 3575);
WIRE 16 -1 (-3650 4675)(-3850 4675);
WIRE 16 -1 (-3450 4625)(-3850 4625);
WIRE 16 -1 (-3850 3525)(-3650 3525);
WIRE 16 -1 (-3450 3475)(-3850 3475);
WIRE 16 -1 (-3850 4575)(-3650 4575);
WIRE 16 -1 (-3450 4525)(-3850 4525);
WIRE 16 -1 (-3650 3425)(-3850 3425);
WIRE 16 -1 (-3850 3375)(-3450 3375);
WIRE 16 -1 (-3650 4475)(-3850 4475);
WIRE 16 -1 (-7500 5375)(-7700 5375);
WIRE 16 -1 (-7500 4775)(-7700 4775);
WIRE 16 -1 (-7500 4925)(-7700 4925);
WIRE 16 -1 (-7500 5325)(-7700 5325);
WIRE 16 -1 (-7500 4625)(-8300 4625);
FORCEPROP 2 LAST SIG_NAME M_A_CPU0_SA_PAR
J 0
(-8300 4635);
DISPLAY 0.489362 (-8300 4635);
WIRE 16 -1 (-6100 2275)(-6300 2275);
WIRE 16 -1 (-6100 2325)(-6300 2325);
WIRE 16 -1 (-6300 2375)(-6100 2375);
WIRE 16 -1 (-6100 2425)(-6300 2425);
WIRE 16 -1 (-6100 2475)(-6300 2475);
WIRE 16 -1 (-6100 2525)(-6300 2525);
WIRE 16 -1 (-6300 2575)(-6100 2575);
WIRE 16 -1 (-6100 2625)(-6300 2625);
WIRE 16 -1 (-6100 2675)(-6300 2675);
WIRE 16 -1 (-6100 2725)(-6300 2725);
WIRE 16 -1 (-6300 2775)(-6100 2775);
WIRE 16 -1 (-6100 2825)(-6300 2825);
WIRE 16 -1 (-6100 2875)(-6300 2875);
WIRE 16 -1 (-6100 2925)(-6300 2925);
WIRE 16 -1 (-6300 2975)(-6100 2975);
WIRE 16 -1 (-6100 3025)(-6300 3025);
WIRE 16 -1 (-6100 3075)(-6300 3075);
WIRE 16 -1 (-6100 3125)(-6300 3125);
WIRE 16 -1 (-6300 3175)(-6100 3175);
WIRE 16 -1 (-6100 3225)(-6300 3225);
WIRE 16 -1 (-6100 3275)(-6300 3275);
WIRE 16 -1 (-6100 3325)(-6300 3325);
WIRE 16 -1 (-6300 3375)(-6100 3375);
WIRE 16 -1 (-6100 3425)(-6300 3425);
WIRE 16 -1 (-6100 3475)(-6300 3475);
WIRE 16 -1 (-6100 3525)(-6300 3525);
WIRE 16 -1 (-6300 3575)(-6100 3575);
WIRE 16 -1 (-6100 3625)(-6300 3625);
WIRE 16 -1 (-6100 3675)(-6300 3675);
WIRE 16 -1 (-6100 3725)(-6300 3725);
WIRE 16 -1 (-6300 3775)(-6100 3775);
WIRE 16 -1 (-6100 3875)(-6300 3875);
WIRE 16 -1 (-6100 3925)(-6300 3925);
WIRE 16 -1 (-6100 3975)(-6300 3975);
WIRE 16 -1 (-6300 4025)(-6100 4025);
WIRE 16 -1 (-6100 4075)(-6300 4075);
WIRE 16 -1 (-6100 4125)(-6300 4125);
WIRE 16 -1 (-6100 4175)(-6300 4175);
WIRE 16 -1 (-6300 4225)(-6100 4225);
WIRE 16 -1 (-6100 4275)(-6300 4275);
WIRE 16 -1 (-6100 4325)(-6300 4325);
WIRE 16 -1 (-6100 4375)(-6300 4375);
WIRE 16 -1 (-6300 4425)(-6100 4425);
WIRE 16 -1 (-6100 4475)(-6300 4475);
WIRE 16 -1 (-6100 4525)(-6300 4525);
WIRE 16 -1 (-6100 4725)(-6300 4725);
WIRE 16 -1 (-6100 4775)(-6300 4775);
WIRE 16 -1 (-6300 4825)(-6100 4825);
WIRE 16 -1 (-6100 4925)(-6300 4925);
WIRE 16 -1 (-6100 4975)(-6300 4975);
WIRE 16 -1 (-6300 5025)(-6100 5025);
WIRE 16 -1 (-7500 4325)(-8300 4325);
FORCEPROP 2 LAST SIG_NAME M_A_CPU0_SB_CS_N<1>
J 0
(-8300 4335);
DISPLAY 0.489362 (-8300 4335);
WIRE 16 -1 (-7500 4175)(-8300 4175);
FORCEPROP 2 LAST SIG_NAME M_A_CPU0_CLK_DP<0>
J 0
(-8300 4185);
DISPLAY 0.489362 (-8300 4185);
WIRE 16 -1 (-7500 4125)(-8300 4125);
FORCEPROP 2 LAST SIG_NAME M_A_CPU0_CLK_DN<0>
J 0
(-8300 4135);
DISPLAY 0.489362 (-8300 4135);
WIRE 16 -1 (-7500 3225)(-7700 3225);
WIRE 16 -1 (-7500 3325)(-7700 3325);
WIRE 16 -1 (-7500 3375)(-7700 3375);
WIRE 16 -1 (-7500 3425)(-7700 3425);
WIRE 16 -1 (-7500 3475)(-7700 3475);
WIRE 16 -1 (-7500 3925)(-7700 3925);
WIRE 16 -1 (-7500 3975)(-7700 3975);
WIRE 16 -1 (-7500 5025)(-7700 5025);
WIRE 16 -1 (-7500 4875)(-7700 4875);
WIRE 16 -1 (-7500 5275)(-7700 5275);
WIRE 16 -1 (-7500 4825)(-7700 4825);
WIRE 16 -1 (-7500 5225)(-7700 5225);
WIRE 16 -1 (-7500 5175)(-7700 5175);
WIRE 16 -1 (-7500 4725)(-7700 4725);
WIRE 16 -1 (-7500 4025)(-7700 4025);
WIRE 16 -1 (-6500 1500)(-6500 1425);
WIRE 16 -1 (-6500 1500)(-7225 1500);
FORCEPROP 2 LAST SIG_NAME PD_CHA_CPU0_DIMM0_SAA
J 0
(-7210 1510);
DISPLAY 0.489362 (-7210 1510);
DOT 1 (-2375 6250);
DOT 1 (-2950 6250);
DOT 1 (-2950 5825);
DOT 1 (-650 2050);
DOT 1 (-650 2000);
DOT 1 (-650 2100);
DOT 1 (-650 2200);
DOT 1 (-8875 3400);
DOT 1 (-2250 5350);
DOT 1 (-2250 5300);
DOT 1 (-2250 4000);
DOT 1 (-2250 5150);
DOT 1 (-2250 3650);
DOT 1 (-2250 2850);
DOT 1 (-2250 4800);
DOT 1 (-650 5050);
DOT 1 (-650 4950);
DOT 1 (-650 2450);
DOT 1 (-650 5300);
DOT 1 (-650 5250);
DOT 1 (-650 5150);
DOT 1 (-650 5200);
DOT 1 (-650 5100);
DOT 1 (-650 5000);
DOT 1 (-650 4900);
DOT 1 (-650 4850);
DOT 1 (-650 4750);
DOT 1 (-650 4800);
DOT 1 (-650 4650);
DOT 1 (-650 4600);
DOT 1 (-650 4500);
DOT 1 (-650 4400);
DOT 1 (-650 4450);
DOT 1 (-650 4350);
DOT 1 (-650 4300);
DOT 1 (-650 4250);
DOT 1 (-650 4150);
DOT 1 (-2250 5100);
DOT 1 (-2250 5000);
DOT 1 (-2250 4900);
DOT 1 (-2250 4250);
DOT 1 (-2250 4200);
DOT 1 (-2250 4150);
DOT 1 (-2250 4100);
DOT 1 (-650 4000);
DOT 1 (-650 4050);
DOT 1 (-650 3950);
DOT 1 (-650 3900);
DOT 1 (-650 3850);
DOT 1 (-650 3750);
DOT 1 (-650 3800);
DOT 1 (-650 3700);
DOT 1 (-650 3650);
DOT 1 (-650 3600);
DOT 1 (-650 3550);
DOT 1 (-650 3500);
DOT 1 (-650 3450);
DOT 1 (-650 3400);
DOT 1 (-650 3350);
DOT 1 (-650 3250);
DOT 1 (-650 3300);
DOT 1 (-650 3100);
DOT 1 (-650 3200);
DOT 1 (-650 3150);
DOT 1 (-650 3050);
DOT 1 (-650 3000);
DOT 1 (-650 2950);
DOT 1 (-650 2850);
DOT 1 (-650 2900);
DOT 1 (-650 2800);
DOT 1 (-650 2750);
DOT 1 (-650 2700);
DOT 1 (-650 2600);
DOT 1 (-650 2650);
DOT 1 (-650 2550);
DOT 1 (-650 2500);
DOT 1 (-650 2350);
DOT 1 (-650 2400);
DOT 1 (-650 2300);
DOT 1 (-650 2250);
DOT 1 (-2250 4050);
DOT 1 (-2250 3950);
DOT 1 (-2250 3900);
DOT 1 (-2250 3850);
DOT 1 (-2250 3750);
DOT 1 (-2250 3700);
DOT 1 (-2250 3600);
DOT 1 (-2250 3550);
DOT 1 (-2250 3500);
DOT 1 (-2250 3450);
DOT 1 (-2250 3400);
DOT 1 (-2250 3350);
DOT 1 (-2250 3300);
DOT 1 (-2250 3250);
DOT 1 (-2250 3100);
DOT 1 (-2250 3200);
DOT 1 (-2250 3150);
DOT 1 (-2250 3050);
DOT 1 (-2250 3000);
DOT 1 (-2250 2950);
DOT 1 (-2250 2900);
DOT 1 (-2250 2800);
DOT 1 (-2250 2750);
DOT 1 (-2250 2700);
DOT 1 (-2250 2600);
DOT 1 (-2250 2650);
DOT 1 (-2250 2550);
DOT 1 (-2250 2500);
DOT 1 (-2250 2450);
DOT 1 (-2250 2350);
DOT 1 (-2250 2400);
DOT 1 (-2250 2300);
DOT 1 (-2250 2250);
DOT 1 (-2250 2200);
DOT 1 (-2250 2100);
DOT 1 (-2250 2150);
DOT 1 (-2250 4300);
DOT 1 (-2250 4700);
DOT 1 (-2250 4650);
DOT 1 (-2250 4600);
DOT 1 (-2250 4550);
DOT 1 (-2250 4500);
DOT 1 (-2250 4450);
DOT 1 (-650 4550);
DOT 1 (-650 4200);
DOT 1 (-650 4100);
DOT 1 (-2250 4350);
DOT 1 (-2250 4400);
DOT 1 (-8700 2250);
DOT 1 (-8450 2250);
DOT 1 (-2250 4850);
DOT 1 (-2250 5050);
DOT 1 (-2250 4950);
DOT 1 (-650 4700);
DOT 1 (-2250 4750);
DOT 1 (-2250 3800);
QUIT
